(kicad_sch
	(version 20250114)
	(generator "eeschema")
	(generator_version "9.0")
	(paper "A3")
	(title_block
		(title "OCuLink to PCIe adapter")
		(date "2025-06-18")
		(rev "1.0.0")
		(company "Antmicro Ltd")
		(comment 1 "www.antmicro.com")
	)
	(text "If 3V3 is good that means\n+12V is also good since it has UVLO"
		(exclude_from_sim no)
		(at 113.03 212.09 0)
		(effects
			(font
				(size 1.27 1.27)
			)
			(justify left)
		)
	)
	(text "Power supply ORing"
		(exclude_from_sim no)
		(at 90.17 52.07 0)
		(effects
			(font
				(size 2 2)
				(thickness 0.4)
				(bold yes)
			)
			(justify left bottom)
		)
	)
	(text "Powers need to be OK and host needs to want\ndevice out of reset for ~{PERST} to be deasserted"
		(exclude_from_sim no)
		(at 93.345 272.415 0)
		(effects
			(font
				(size 1.27 1.27)
			)
			(justify left)
		)
	)
	(text "V_{out} = 3.3 V\nf_{SW} = 500 kHz"
		(exclude_from_sim no)
		(at 316.738 94.742 0)
		(effects
			(font
				(size 1.27 1.27)
			)
			(justify left bottom)
		)
	)
	(text "+3V3 DC/DC converter"
		(exclude_from_sim no)
		(at 292.1 50.8 0)
		(effects
			(font
				(size 2 2)
				(thickness 0.4)
				(bold yes)
			)
			(justify left bottom)
		)
	)
	(text "10.0V UVLO\n(V_{ENH} = 1.3V)"
		(exclude_from_sim no)
		(at 256.286 110.998 0)
		(effects
			(font
				(size 1.27 1.27)
			)
		)
	)
	(text "Power indicator LEDs and testpoints"
		(exclude_from_sim no)
		(at 279.4 177.8 0)
		(effects
			(font
				(size 2 2)
				(thickness 0.4)
				(bold yes)
			)
			(justify left bottom)
		)
	)
	(text "~{PERST} and ~{CPRSNT} control"
		(exclude_from_sim no)
		(at 88.9 177.8 0)
		(effects
			(font
				(size 2 2)
				(thickness 0.4)
				(bold yes)
			)
			(justify left bottom)
		)
	)
	(junction
		(at 292.1 90.17)
		(diameter 0)
		(color 0 0 0 0)
	)
	(junction
		(at 81.28 92.71)
		(diameter 0)
		(color 0 0 0 0)
	)
	(junction
		(at 361.95 82.55)
		(diameter 0)
		(color 0 0 0 0)
	)
	(junction
		(at 350.52 77.47)
		(diameter 0)
		(color 0 0 0 0)
	)
	(junction
		(at 127 100.33)
		(diameter 0)
		(color 0 0 0 0)
	)
	(junction
		(at 233.68 72.39)
		(diameter 0)
		(color 0 0 0 0)
	)
	(junction
		(at 81.28 118.11)
		(diameter 0)
		(color 0 0 0 0)
	)
	(junction
		(at 242.57 72.39)
		(diameter 0)
		(color 0 0 0 0)
	)
	(junction
		(at 127 76.2)
		(diameter 0)
		(color 0 0 0 0)
	)
	(junction
		(at 88.9 92.71)
		(diameter 0)
		(color 0 0 0 0)
	)
	(junction
		(at 271.78 95.25)
		(diameter 0)
		(color 0 0 0 0)
	)
	(junction
		(at 246.38 72.39)
		(diameter 0)
		(color 0 0 0 0)
	)
	(junction
		(at 91.44 254)
		(diameter 0)
		(color 0 0 0 0)
	)
	(junction
		(at 335.28 87.63)
		(diameter 0)
		(color 0 0 0 0)
	)
	(junction
		(at 88.9 118.11)
		(diameter 0)
		(color 0 0 0 0)
	)
	(junction
		(at 335.28 77.47)
		(diameter 0)
		(color 0 0 0 0)
	)
	(junction
		(at 73.66 248.92)
		(diameter 0)
		(color 0 0 0 0)
	)
	(junction
		(at 313.69 95.25)
		(diameter 0)
		(color 0 0 0 0)
	)
	(junction
		(at 257.81 72.39)
		(diameter 0)
		(color 0 0 0 0)
	)
	(junction
		(at 271.78 82.55)
		(diameter 0)
		(color 0 0 0 0)
	)
	(junction
		(at 85.09 118.11)
		(diameter 0)
		(color 0 0 0 0)
	)
	(junction
		(at 317.5 198.12)
		(diameter 0)
		(color 0 0 0 0)
	)
	(junction
		(at 361.95 77.47)
		(diameter 0)
		(color 0 0 0 0)
	)
	(junction
		(at 127 67.31)
		(diameter 0)
		(color 0 0 0 0)
	)
	(junction
		(at 379.73 77.47)
		(diameter 0)
		(color 0 0 0 0)
	)
	(junction
		(at 256.54 77.47)
		(diameter 0)
		(color 0 0 0 0)
	)
	(junction
		(at 123.19 254)
		(diameter 0)
		(color 0 0 0 0)
	)
	(junction
		(at 304.8 195.58)
		(diameter 0)
		(color 0 0 0 0)
	)
	(junction
		(at 85.09 236.22)
		(diameter 0)
		(color 0 0 0 0)
	)
	(junction
		(at 92.71 203.2)
		(diameter 0)
		(color 0 0 0 0)
	)
	(junction
		(at 292.1 82.55)
		(diameter 0)
		(color 0 0 0 0)
	)
	(junction
		(at 85.09 92.71)
		(diameter 0)
		(color 0 0 0 0)
	)
	(junction
		(at 127 92.71)
		(diameter 0)
		(color 0 0 0 0)
	)
	(junction
		(at 223.52 72.39)
		(diameter 0)
		(color 0 0 0 0)
	)
	(junction
		(at 209.55 100.33)
		(diameter 0)
		(color 0 0 0 0)
	)
	(junction
		(at 135.89 76.2)
		(diameter 0)
		(color 0 0 0 0)
	)
	(junction
		(at 132.08 254)
		(diameter 0)
		(color 0 0 0 0)
	)
	(junction
		(at 281.94 227.33)
		(diameter 0)
		(color 0 0 0 0)
	)
	(junction
		(at 347.98 77.47)
		(diameter 0)
		(color 0 0 0 0)
	)
	(junction
		(at 339.09 77.47)
		(diameter 0)
		(color 0 0 0 0)
	)
	(junction
		(at 325.12 77.47)
		(diameter 0)
		(color 0 0 0 0)
	)
	(no_connect
		(at 311.15 87.63)
	)
	(wire
		(pts
			(xy 91.44 259.08) (xy 92.71 259.08)
		)
		(stroke
			(width 0)
			(type default)
		)
	)
	(wire
		(pts
			(xy 304.8 208.28) (xy 304.8 210.82)
		)
		(stroke
			(width 0)
			(type default)
		)
	)
	(wire
		(pts
			(xy 313.69 102.87) (xy 313.69 95.25)
		)
		(stroke
			(width 0)
			(type default)
		)
	)
	(wire
		(pts
			(xy 107.95 191.77) (xy 105.41 191.77)
		)
		(stroke
			(width 0)
			(type default)
		)
	)
	(wire
		(pts
			(xy 76.2 203.2) (xy 92.71 203.2)
		)
		(stroke
			(width 0)
			(type default)
		)
	)
	(wire
		(pts
			(xy 311.15 95.25) (xy 313.69 95.25)
		)
		(stroke
			(width 0)
			(type default)
		)
	)
	(wire
		(pts
			(xy 311.15 77.47) (xy 325.12 77.47)
		)
		(stroke
			(width 0)
			(type default)
		)
	)
	(wire
		(pts
			(xy 379.73 73.66) (xy 379.73 77.47)
		)
		(stroke
			(width 0)
			(type default)
		)
	)
	(wire
		(pts
			(xy 325.12 77.47) (xy 327.66 77.47)
		)
		(stroke
			(width 0)
			(type default)
		)
	)
	(wire
		(pts
			(xy 379.73 77.47) (xy 373.38 77.47)
		)
		(stroke
			(width 0)
			(type default)
		)
	)
	(wire
		(pts
			(xy 332.74 77.47) (xy 335.28 77.47)
		)
		(stroke
			(width 0)
			(type default)
		)
	)
	(wire
		(pts
			(xy 325.12 87.63) (xy 335.28 87.63)
		)
		(stroke
			(width 0)
			(type default)
		)
	)
	(wire
		(pts
			(xy 271.78 82.55) (xy 292.1 82.55)
		)
		(stroke
			(width 0)
			(type default)
		)
	)
	(wire
		(pts
			(xy 292.1 208.28) (xy 292.1 210.82)
		)
		(stroke
			(width 0)
			(type default)
		)
	)
	(wire
		(pts
			(xy 132.08 254) (xy 132.08 255.27)
		)
		(stroke
			(width 0)
			(type default)
		)
	)
	(wire
		(pts
			(xy 292.1 233.68) (xy 292.1 231.14)
		)
		(stroke
			(width 0)
			(type default)
		)
	)
	(wire
		(pts
			(xy 105.41 213.36) (xy 105.41 207.01)
		)
		(stroke
			(width 0)
			(type default)
		)
	)
	(wire
		(pts
			(xy 335.28 77.47) (xy 335.28 80.01)
		)
		(stroke
			(width 0)
			(type default)
		)
	)
	(wire
		(pts
			(xy 90.17 246.38) (xy 92.71 246.38)
		)
		(stroke
			(width 0)
			(type default)
		)
	)
	(wire
		(pts
			(xy 335.28 226.06) (xy 334.01 226.06)
		)
		(stroke
			(width 0)
			(type default)
		)
	)
	(wire
		(pts
			(xy 292.1 88.9) (xy 292.1 90.17)
		)
		(stroke
			(width 0)
			(type default)
		)
	)
	(wire
		(pts
			(xy 209.55 100.33) (xy 209.55 102.87)
		)
		(stroke
			(width 0)
			(type default)
		)
	)
	(wire
		(pts
			(xy 88.9 118.11) (xy 95.25 118.11)
		)
		(stroke
			(width 0)
			(type default)
		)
	)
	(wire
		(pts
			(xy 273.05 227.33) (xy 281.94 227.33)
		)
		(stroke
			(width 0)
			(type default)
		)
	)
	(wire
		(pts
			(xy 64.77 118.11) (xy 69.85 118.11)
		)
		(stroke
			(width 0)
			(type default)
		)
	)
	(wire
		(pts
			(xy 311.15 82.55) (xy 325.12 82.55)
		)
		(stroke
			(width 0)
			(type default)
		)
	)
	(wire
		(pts
			(xy 92.71 203.2) (xy 97.79 203.2)
		)
		(stroke
			(width 0)
			(type default)
		)
	)
	(wire
		(pts
			(xy 304.8 195.58) (xy 322.58 195.58)
		)
		(stroke
			(width 0)
			(type default)
		)
	)
	(wire
		(pts
			(xy 313.69 92.71) (xy 313.69 95.25)
		)
		(stroke
			(width 0)
			(type default)
		)
	)
	(wire
		(pts
			(xy 110.49 248.92) (xy 118.11 248.92)
		)
		(stroke
			(width 0)
			(type default)
		)
	)
	(wire
		(pts
			(xy 200.66 100.33) (xy 209.55 100.33)
		)
		(stroke
			(width 0)
			(type default)
		)
	)
	(wire
		(pts
			(xy 81.28 254) (xy 91.44 254)
		)
		(stroke
			(width 0)
			(type default)
		)
	)
	(wire
		(pts
			(xy 257.81 72.39) (xy 293.37 72.39)
		)
		(stroke
			(width 0)
			(type default)
		)
	)
	(wire
		(pts
			(xy 368.3 77.47) (xy 361.95 77.47)
		)
		(stroke
			(width 0)
			(type default)
		)
	)
	(wire
		(pts
			(xy 256.54 77.47) (xy 293.37 77.47)
		)
		(stroke
			(width 0)
			(type default)
		)
	)
	(wire
		(pts
			(xy 246.38 72.39) (xy 246.38 77.47)
		)
		(stroke
			(width 0)
			(type default)
		)
	)
	(wire
		(pts
			(xy 88.9 115.57) (xy 88.9 118.11)
		)
		(stroke
			(width 0)
			(type default)
		)
	)
	(wire
		(pts
			(xy 325.12 72.39) (xy 325.12 77.47)
		)
		(stroke
			(width 0)
			(type default)
		)
	)
	(wire
		(pts
			(xy 90.17 236.22) (xy 90.17 246.38)
		)
		(stroke
			(width 0)
			(type default)
		)
	)
	(wire
		(pts
			(xy 97.79 264.16) (xy 114.3 264.16)
		)
		(stroke
			(width 0)
			(type default)
		)
	)
	(wire
		(pts
			(xy 317.5 208.28) (xy 317.5 210.82)
		)
		(stroke
			(width 0)
			(type default)
		)
	)
	(wire
		(pts
			(xy 85.09 125.73) (xy 85.09 128.27)
		)
		(stroke
			(width 0)
			(type default)
		)
	)
	(wire
		(pts
			(xy 81.28 92.71) (xy 81.28 90.17)
		)
		(stroke
			(width 0)
			(type default)
		)
	)
	(wire
		(pts
			(xy 242.57 102.87) (xy 242.57 90.17)
		)
		(stroke
			(width 0)
			(type default)
		)
	)
	(wire
		(pts
			(xy 382.27 81.28) (xy 379.73 81.28)
		)
		(stroke
			(width 0)
			(type default)
		)
	)
	(wire
		(pts
			(xy 361.95 82.55) (xy 361.95 88.9)
		)
		(stroke
			(width 0)
			(type default)
		)
	)
	(wire
		(pts
			(xy 325.12 82.55) (xy 325.12 87.63)
		)
		(stroke
			(width 0)
			(type default)
		)
	)
	(wire
		(pts
			(xy 85.09 234.95) (xy 85.09 236.22)
		)
		(stroke
			(width 0)
			(type default)
		)
	)
	(wire
		(pts
			(xy 128.27 100.33) (xy 127 100.33)
		)
		(stroke
			(width 0)
			(type default)
		)
	)
	(wire
		(pts
			(xy 91.44 260.35) (xy 91.44 259.08)
		)
		(stroke
			(width 0)
			(type default)
		)
	)
	(wire
		(pts
			(xy 281.94 223.52) (xy 281.94 227.33)
		)
		(stroke
			(width 0)
			(type default)
		)
	)
	(wire
		(pts
			(xy 292.1 82.55) (xy 293.37 82.55)
		)
		(stroke
			(width 0)
			(type default)
		)
	)
	(wire
		(pts
			(xy 85.09 118.11) (xy 81.28 118.11)
		)
		(stroke
			(width 0)
			(type default)
		)
	)
	(wire
		(pts
			(xy 256.54 97.79) (xy 256.54 102.87)
		)
		(stroke
			(width 0)
			(type default)
		)
	)
	(wire
		(pts
			(xy 281.94 227.33) (xy 284.48 227.33)
		)
		(stroke
			(width 0)
			(type default)
		)
	)
	(wire
		(pts
			(xy 120.65 67.31) (xy 127 67.31)
		)
		(stroke
			(width 0)
			(type default)
		)
	)
	(wire
		(pts
			(xy 271.78 95.25) (xy 293.37 95.25)
		)
		(stroke
			(width 0)
			(type default)
		)
	)
	(wire
		(pts
			(xy 135.89 87.63) (xy 135.89 88.9)
		)
		(stroke
			(width 0)
			(type default)
		)
	)
	(wire
		(pts
			(xy 127 92.71) (xy 127 100.33)
		)
		(stroke
			(width 0)
			(type default)
		)
	)
	(wire
		(pts
			(xy 64.77 92.71) (xy 69.85 92.71)
		)
		(stroke
			(width 0)
			(type default)
		)
	)
	(wire
		(pts
			(xy 64.77 67.31) (xy 95.25 67.31)
		)
		(stroke
			(width 0)
			(type default)
		)
	)
	(wire
		(pts
			(xy 233.68 72.39) (xy 233.68 85.09)
		)
		(stroke
			(width 0)
			(type default)
		)
	)
	(wire
		(pts
			(xy 271.78 101.6) (xy 271.78 102.87)
		)
		(stroke
			(width 0)
			(type default)
		)
	)
	(wire
		(pts
			(xy 292.1 82.55) (xy 292.1 83.82)
		)
		(stroke
			(width 0)
			(type default)
		)
	)
	(wire
		(pts
			(xy 74.93 92.71) (xy 81.28 92.71)
		)
		(stroke
			(width 0)
			(type default)
		)
	)
	(wire
		(pts
			(xy 67.31 248.92) (xy 73.66 248.92)
		)
		(stroke
			(width 0)
			(type default)
		)
	)
	(wire
		(pts
			(xy 88.9 92.71) (xy 95.25 92.71)
		)
		(stroke
			(width 0)
			(type default)
		)
	)
	(wire
		(pts
			(xy 85.09 92.71) (xy 88.9 92.71)
		)
		(stroke
			(width 0)
			(type default)
		)
	)
	(wire
		(pts
			(xy 335.28 85.09) (xy 335.28 87.63)
		)
		(stroke
			(width 0)
			(type default)
		)
	)
	(wire
		(pts
			(xy 85.09 100.33) (xy 85.09 102.87)
		)
		(stroke
			(width 0)
			(type default)
		)
	)
	(wire
		(pts
			(xy 73.66 248.92) (xy 92.71 248.92)
		)
		(stroke
			(width 0)
			(type default)
		)
	)
	(wire
		(pts
			(xy 350.52 77.47) (xy 350.52 88.9)
		)
		(stroke
			(width 0)
			(type default)
		)
	)
	(wire
		(pts
			(xy 271.78 82.55) (xy 271.78 87.63)
		)
		(stroke
			(width 0)
			(type default)
		)
	)
	(wire
		(pts
			(xy 123.19 254) (xy 132.08 254)
		)
		(stroke
			(width 0)
			(type default)
		)
	)
	(wire
		(pts
			(xy 361.95 77.47) (xy 361.95 82.55)
		)
		(stroke
			(width 0)
			(type default)
		)
	)
	(wire
		(pts
			(xy 311.15 92.71) (xy 313.69 92.71)
		)
		(stroke
			(width 0)
			(type default)
		)
	)
	(wire
		(pts
			(xy 271.78 92.71) (xy 271.78 95.25)
		)
		(stroke
			(width 0)
			(type default)
		)
	)
	(wire
		(pts
			(xy 350.52 102.87) (xy 350.52 93.98)
		)
		(stroke
			(width 0)
			(type default)
		)
	)
	(wire
		(pts
			(xy 257.81 69.85) (xy 257.81 72.39)
		)
		(stroke
			(width 0)
			(type default)
		)
	)
	(wire
		(pts
			(xy 317.5 190.5) (xy 317.5 198.12)
		)
		(stroke
			(width 0)
			(type default)
		)
	)
	(wire
		(pts
			(xy 81.28 251.46) (xy 92.71 251.46)
		)
		(stroke
			(width 0)
			(type default)
		)
	)
	(wire
		(pts
			(xy 91.44 254) (xy 92.71 254)
		)
		(stroke
			(width 0)
			(type default)
		)
	)
	(wire
		(pts
			(xy 127 100.33) (xy 127 118.11)
		)
		(stroke
			(width 0)
			(type default)
		)
	)
	(wire
		(pts
			(xy 88.9 90.17) (xy 88.9 92.71)
		)
		(stroke
			(width 0)
			(type default)
		)
	)
	(wire
		(pts
			(xy 292.1 190.5) (xy 292.1 203.2)
		)
		(stroke
			(width 0)
			(type default)
		)
	)
	(wire
		(pts
			(xy 123.19 264.16) (xy 123.19 254)
		)
		(stroke
			(width 0)
			(type default)
		)
	)
	(wire
		(pts
			(xy 85.09 92.71) (xy 85.09 95.25)
		)
		(stroke
			(width 0)
			(type default)
		)
	)
	(wire
		(pts
			(xy 119.38 254) (xy 123.19 254)
		)
		(stroke
			(width 0)
			(type default)
		)
	)
	(wire
		(pts
			(xy 304.8 215.9) (xy 304.8 233.68)
		)
		(stroke
			(width 0)
			(type default)
		)
	)
	(wire
		(pts
			(xy 254 77.47) (xy 256.54 77.47)
		)
		(stroke
			(width 0)
			(type default)
		)
	)
	(wire
		(pts
			(xy 120.65 92.71) (xy 127 92.71)
		)
		(stroke
			(width 0)
			(type default)
		)
	)
	(wire
		(pts
			(xy 110.49 254) (xy 114.3 254)
		)
		(stroke
			(width 0)
			(type default)
		)
	)
	(wire
		(pts
			(xy 292.1 215.9) (xy 292.1 218.44)
		)
		(stroke
			(width 0)
			(type default)
		)
	)
	(wire
		(pts
			(xy 246.38 72.39) (xy 242.57 72.39)
		)
		(stroke
			(width 0)
			(type default)
		)
	)
	(wire
		(pts
			(xy 246.38 72.39) (xy 257.81 72.39)
		)
		(stroke
			(width 0)
			(type default)
		)
	)
	(wire
		(pts
			(xy 335.28 95.25) (xy 335.28 102.87)
		)
		(stroke
			(width 0)
			(type default)
		)
	)
	(wire
		(pts
			(xy 347.98 77.47) (xy 350.52 77.47)
		)
		(stroke
			(width 0)
			(type default)
		)
	)
	(wire
		(pts
			(xy 292.1 90.17) (xy 293.37 90.17)
		)
		(stroke
			(width 0)
			(type default)
		)
	)
	(wire
		(pts
			(xy 339.09 77.47) (xy 347.98 77.47)
		)
		(stroke
			(width 0)
			(type default)
		)
	)
	(wire
		(pts
			(xy 85.09 236.22) (xy 85.09 237.49)
		)
		(stroke
			(width 0)
			(type default)
		)
	)
	(wire
		(pts
			(xy 127 64.77) (xy 127 67.31)
		)
		(stroke
			(width 0)
			(type default)
		)
	)
	(wire
		(pts
			(xy 85.09 118.11) (xy 88.9 118.11)
		)
		(stroke
			(width 0)
			(type default)
		)
	)
	(wire
		(pts
			(xy 120.65 118.11) (xy 127 118.11)
		)
		(stroke
			(width 0)
			(type default)
		)
	)
	(wire
		(pts
			(xy 279.4 90.17) (xy 292.1 90.17)
		)
		(stroke
			(width 0)
			(type default)
		)
	)
	(wire
		(pts
			(xy 105.41 191.77) (xy 105.41 194.31)
		)
		(stroke
			(width 0)
			(type default)
		)
	)
	(wire
		(pts
			(xy 91.44 254) (xy 91.44 256.54)
		)
		(stroke
			(width 0)
			(type default)
		)
	)
	(wire
		(pts
			(xy 233.68 72.39) (xy 242.57 72.39)
		)
		(stroke
			(width 0)
			(type default)
		)
	)
	(wire
		(pts
			(xy 317.5 198.12) (xy 322.58 198.12)
		)
		(stroke
			(width 0)
			(type default)
		)
	)
	(wire
		(pts
			(xy 334.01 226.06) (xy 334.01 227.33)
		)
		(stroke
			(width 0)
			(type default)
		)
	)
	(wire
		(pts
			(xy 85.09 236.22) (xy 90.17 236.22)
		)
		(stroke
			(width 0)
			(type default)
		)
	)
	(wire
		(pts
			(xy 242.57 72.39) (xy 242.57 85.09)
		)
		(stroke
			(width 0)
			(type default)
		)
	)
	(wire
		(pts
			(xy 246.38 77.47) (xy 248.92 77.47)
		)
		(stroke
			(width 0)
			(type default)
		)
	)
	(wire
		(pts
			(xy 74.93 118.11) (xy 81.28 118.11)
		)
		(stroke
			(width 0)
			(type default)
		)
	)
	(wire
		(pts
			(xy 304.8 190.5) (xy 304.8 195.58)
		)
		(stroke
			(width 0)
			(type default)
		)
	)
	(wire
		(pts
			(xy 304.8 195.58) (xy 304.8 203.2)
		)
		(stroke
			(width 0)
			(type default)
		)
	)
	(wire
		(pts
			(xy 132.08 254) (xy 139.7 254)
		)
		(stroke
			(width 0)
			(type default)
		)
	)
	(wire
		(pts
			(xy 200.66 97.79) (xy 200.66 100.33)
		)
		(stroke
			(width 0)
			(type default)
		)
	)
	(wire
		(pts
			(xy 92.71 210.82) (xy 92.71 213.36)
		)
		(stroke
			(width 0)
			(type default)
		)
	)
	(wire
		(pts
			(xy 233.68 102.87) (xy 233.68 90.17)
		)
		(stroke
			(width 0)
			(type default)
		)
	)
	(wire
		(pts
			(xy 135.89 76.2) (xy 147.32 76.2)
		)
		(stroke
			(width 0)
			(type default)
		)
	)
	(wire
		(pts
			(xy 350.52 77.47) (xy 361.95 77.47)
		)
		(stroke
			(width 0)
			(type default)
		)
	)
	(wire
		(pts
			(xy 85.09 118.11) (xy 85.09 120.65)
		)
		(stroke
			(width 0)
			(type default)
		)
	)
	(wire
		(pts
			(xy 127 76.2) (xy 127 92.71)
		)
		(stroke
			(width 0)
			(type default)
		)
	)
	(wire
		(pts
			(xy 223.52 72.39) (xy 233.68 72.39)
		)
		(stroke
			(width 0)
			(type default)
		)
	)
	(wire
		(pts
			(xy 271.78 82.55) (xy 264.16 82.55)
		)
		(stroke
			(width 0)
			(type default)
		)
	)
	(wire
		(pts
			(xy 73.66 248.92) (xy 73.66 250.19)
		)
		(stroke
			(width 0)
			(type default)
		)
	)
	(wire
		(pts
			(xy 147.32 76.2) (xy 147.32 82.55)
		)
		(stroke
			(width 0)
			(type default)
		)
	)
	(wire
		(pts
			(xy 264.16 102.87) (xy 264.16 97.79)
		)
		(stroke
			(width 0)
			(type default)
		)
	)
	(wire
		(pts
			(xy 361.95 102.87) (xy 361.95 93.98)
		)
		(stroke
			(width 0)
			(type default)
		)
	)
	(wire
		(pts
			(xy 271.78 95.25) (xy 271.78 96.52)
		)
		(stroke
			(width 0)
			(type default)
		)
	)
	(wire
		(pts
			(xy 127 67.31) (xy 127 76.2)
		)
		(stroke
			(width 0)
			(type default)
		)
	)
	(wire
		(pts
			(xy 347.98 77.47) (xy 347.98 73.66)
		)
		(stroke
			(width 0)
			(type default)
		)
	)
	(wire
		(pts
			(xy 339.09 73.66) (xy 339.09 77.47)
		)
		(stroke
			(width 0)
			(type default)
		)
	)
	(wire
		(pts
			(xy 311.15 72.39) (xy 320.04 72.39)
		)
		(stroke
			(width 0)
			(type default)
		)
	)
	(wire
		(pts
			(xy 223.52 90.17) (xy 223.52 102.87)
		)
		(stroke
			(width 0)
			(type default)
		)
	)
	(wire
		(pts
			(xy 361.95 82.55) (xy 363.22 82.55)
		)
		(stroke
			(width 0)
			(type default)
		)
	)
	(wire
		(pts
			(xy 264.16 82.55) (xy 264.16 92.71)
		)
		(stroke
			(width 0)
			(type default)
		)
	)
	(wire
		(pts
			(xy 81.28 92.71) (xy 85.09 92.71)
		)
		(stroke
			(width 0)
			(type default)
		)
	)
	(wire
		(pts
			(xy 317.5 198.12) (xy 317.5 203.2)
		)
		(stroke
			(width 0)
			(type default)
		)
	)
	(polyline
		(pts
			(xy 198.12 12.7) (xy 198.12 285.75)
		)
		(stroke
			(width 0)
			(type dash)
		)
	)
	(wire
		(pts
			(xy 119.38 264.16) (xy 123.19 264.16)
		)
		(stroke
			(width 0)
			(type default)
		)
	)
	(wire
		(pts
			(xy 127 76.2) (xy 135.89 76.2)
		)
		(stroke
			(width 0)
			(type default)
		)
	)
	(wire
		(pts
			(xy 147.32 87.63) (xy 147.32 88.9)
		)
		(stroke
			(width 0)
			(type default)
		)
	)
	(wire
		(pts
			(xy 335.28 87.63) (xy 335.28 90.17)
		)
		(stroke
			(width 0)
			(type default)
		)
	)
	(wire
		(pts
			(xy 379.73 81.28) (xy 379.73 77.47)
		)
		(stroke
			(width 0)
			(type default)
		)
	)
	(wire
		(pts
			(xy 223.52 72.39) (xy 223.52 85.09)
		)
		(stroke
			(width 0)
			(type default)
		)
	)
	(wire
		(pts
			(xy 256.54 77.47) (xy 256.54 92.71)
		)
		(stroke
			(width 0)
			(type default)
		)
	)
	(wire
		(pts
			(xy 92.71 256.54) (xy 91.44 256.54)
		)
		(stroke
			(width 0)
			(type default)
		)
	)
	(wire
		(pts
			(xy 92.71 203.2) (xy 92.71 205.74)
		)
		(stroke
			(width 0)
			(type default)
		)
	)
	(wire
		(pts
			(xy 135.89 76.2) (xy 135.89 82.55)
		)
		(stroke
			(width 0)
			(type default)
		)
	)
	(wire
		(pts
			(xy 335.28 77.47) (xy 339.09 77.47)
		)
		(stroke
			(width 0)
			(type default)
		)
	)
	(polyline
		(pts
			(xy 12.7 152.4) (xy 407.67 152.4)
		)
		(stroke
			(width 0)
			(type dash)
		)
	)
	(wire
		(pts
			(xy 81.28 118.11) (xy 81.28 115.57)
		)
		(stroke
			(width 0)
			(type default)
		)
	)
	(wire
		(pts
			(xy 223.52 69.85) (xy 223.52 72.39)
		)
		(stroke
			(width 0)
			(type default)
		)
	)
	(wire
		(pts
			(xy 317.5 215.9) (xy 317.5 233.68)
		)
		(stroke
			(width 0)
			(type default)
		)
	)
	(wire
		(pts
			(xy 379.73 77.47) (xy 381 77.47)
		)
		(stroke
			(width 0)
			(type default)
		)
	)
	(wire
		(pts
			(xy 209.55 97.79) (xy 209.55 100.33)
		)
		(stroke
			(width 0)
			(type default)
		)
	)
	(label "3V3_FB"
		(at 320.04 82.55 180)
		(effects
			(font
				(size 1.27 1.27)
			)
			(justify right bottom)
		)
	)
	(label "3V3_BST"
		(at 320.04 72.39 180)
		(effects
			(font
				(size 1.27 1.27)
			)
			(justify right bottom)
		)
	)
	(label "~{PERST}"
		(at 273.05 227.33 0)
		(effects
			(font
				(size 1.27 1.27)
			)
			(justify left bottom)
		)
	)
	(label "~{PERST_CONN}"
		(at 97.79 264.16 0)
		(effects
			(font
				(size 1.27 1.27)
			)
			(justify left bottom)
		)
	)
	(label "3V3_SW"
		(at 320.04 77.47 180)
		(effects
			(font
				(size 1.27 1.27)
			)
			(justify right bottom)
		)
	)
	(label "3V3_PG"
		(at 76.2 203.2 0)
		(effects
			(font
				(size 1.27 1.27)
			)
			(justify left bottom)
		)
	)
	(label "3V3_CONV"
		(at 354.33 77.47 0)
		(effects
			(font
				(size 1.27 1.27)
			)
			(justify left bottom)
		)
	)
	(label "3V3_MODE"
		(at 279.4 95.25 0)
		(effects
			(font
				(size 1.27 1.27)
			)
			(justify left bottom)
		)
	)
	(label "3V3_EN"
		(at 279.4 77.47 0)
		(effects
			(font
				(size 1.27 1.27)
			)
			(justify left bottom)
		)
	)
	(label "PERST"
		(at 81.28 254 0)
		(effects
			(font
				(size 1.27 1.27)
			)
			(justify left bottom)
		)
	)
	(label "3V3_VCC"
		(at 279.4 82.55 0)
		(effects
			(font
				(size 1.27 1.27)
			)
			(justify left bottom)
		)
	)
	(label "PERST"
		(at 118.11 248.92 180)
		(effects
			(font
				(size 1.27 1.27)
			)
			(justify right bottom)
		)
	)
	(label "3V3_PG"
		(at 279.4 90.17 0)
		(effects
			(font
				(size 1.27 1.27)
			)
			(justify left bottom)
		)
	)
	(label "3V3_PG"
		(at 81.28 251.46 0)
		(effects
			(font
				(size 1.27 1.27)
			)
			(justify left bottom)
		)
	)
	(hierarchical_label "VCC_DC_CONN_1"
		(shape input)
		(at 64.77 92.71 180)
		(effects
			(font
				(size 1.27 1.27)
			)
			(justify right)
		)
	)
	(hierarchical_label "VCC_PD"
		(shape input)
		(at 64.77 67.31 180)
		(effects
			(font
				(size 1.27 1.27)
			)
			(justify right)
		)
	)
	(hierarchical_label "~{PERST}"
		(shape output)
		(at 139.7 254 0)
		(effects
			(font
				(size 1.27 1.27)
			)
			(justify left)
		)
	)
	(hierarchical_label "~{CPRSNT}"
		(shape output)
		(at 107.95 191.77 0)
		(effects
			(font
				(size 1.27 1.27)
			)
			(justify left)
		)
	)
	(hierarchical_label "~{PERST_CONN}"
		(shape input)
		(at 67.31 248.92 180)
		(effects
			(font
				(size 1.27 1.27)
			)
			(justify right)
		)
	)
	(hierarchical_label "VCC_DC_CONN_2"
		(shape input)
		(at 64.77 118.11 180)
		(effects
			(font
				(size 1.27 1.27)
			)
			(justify right)
		)
	)
	(netclass_flag ""
		(length 2.54)
		(shape round)
		(at 257.81 69.85 0)
		(effects
			(font
				(size 1.27 1.27)
				(color 255 0 0 1)
			)
			(justify left bottom)
		)
		(property "Netclass" "PWR"
			(at 257.81 65.786 0)
			(effects
				(font
					(size 1.27 1.27)
				)
			)
		)
		(property "Component Class" ""
			(at -115.57 25.4 0)
			(effects
				(font
					(size 1.27 1.27)
					(italic yes)
				)
			)
		)
	)
	(netclass_flag ""
		(length 2.54)
		(shape round)
		(at 200.66 97.79 0)
		(effects
			(font
				(size 1.27 1.27)
				(color 0 0 255 1)
			)
			(justify left bottom)
		)
		(property "Netclass" "GND"
			(at 200.66 93.726 0)
			(effects
				(font
					(size 1.27 1.27)
				)
			)
		)
		(property "Component Class" ""
			(at -172.72 53.34 0)
			(effects
				(font
					(size 1.27 1.27)
					(italic yes)
				)
			)
		)
	)
	(netclass_flag ""
		(length 2.54)
		(shape round)
		(at 81.28 90.17 0)
		(effects
			(font
				(size 1.27 1.27)
				(color 255 0 0 1)
			)
			(justify left bottom)
		)
		(property "Netclass" "PWR"
			(at 81.28 86.106 0)
			(effects
				(font
					(size 1.27 1.27)
				)
			)
		)
		(property "Component Class" ""
			(at -292.1 45.72 0)
			(effects
				(font
					(size 1.27 1.27)
					(italic yes)
				)
			)
		)
	)
	(netclass_flag ""
		(length 2.54)
		(shape round)
		(at 81.28 115.57 0)
		(effects
			(font
				(size 1.27 1.27)
				(color 255 0 0 1)
			)
			(justify left bottom)
		)
		(property "Netclass" "PWR"
			(at 81.28 111.506 0)
			(effects
				(font
					(size 1.27 1.27)
				)
			)
		)
		(property "Component Class" ""
			(at -292.1 71.12 0)
			(effects
				(font
					(size 1.27 1.27)
					(italic yes)
				)
			)
		)
	)
	(netclass_flag ""
		(length 2.54)
		(shape round)
		(at 339.09 73.66 0)
		(effects
			(font
				(size 1.27 1.27)
				(color 255 0 0 1)
			)
			(justify left bottom)
		)
		(property "Netclass" "PWR"
			(at 339.09 69.596 0)
			(effects
				(font
					(size 1.27 1.27)
				)
			)
		)
		(property "Component Class" ""
			(at -34.29 29.21 0)
			(effects
				(font
					(size 1.27 1.27)
					(italic yes)
				)
			)
		)
	)
	(netclass_flag ""
		(length 2.54)
		(shape round)
		(at 381 77.47 270)
		(effects
			(font
				(size 1.27 1.27)
				(color 255 0 0 1)
			)
			(justify right bottom)
		)
		(property "Netclass" "PWR"
			(at 384.175 77.47 0)
			(effects
				(font
					(size 1.27 1.27)
				)
				(justify left)
			)
		)
		(property "Component Class" ""
			(at 425.45 -295.91 90)
			(effects
				(font
					(size 1.27 1.27)
					(italic yes)
				)
			)
		)
	)
	(symbol
		(lib_id "antmicroFixedInductors:L_1u8_6.8A_WE-MAPI-4020")
		(at 327.66 77.47 0)
		(unit 1)
		(exclude_from_sim no)
		(in_bom yes)
		(on_board yes)
		(dnp no)
		(fields_autoplaced yes)
		(property "Reference" "L1"
			(at 330.2 72.39 0)
			(effects
				(font
					(size 1.27 1.27)
					(thickness 0.15)
				)
			)
		)
		(property "Value" "L_1u8_6.8A_WE-MAPI-4020"
			(at 341.63 80.01 0)
			(effects
				(font
					(size 1.27 1.27)
					(thickness 0.15)
				)
				(justify left bottom)
				(hide yes)
			)
		)
		(property "Footprint" "antmicro-footprints:L_WE-MAPI-4020"
			(at 341.63 85.09 0)
			(effects
				(font
					(size 1.27 1.27)
					(thickness 0.15)
				)
				(justify left bottom)
				(hide yes)
			)
		)
		(property "Datasheet" "https://www.we-online.com/components/products/datasheet/74438356018.pdf"
			(at 341.63 87.63 0)
			(effects
				(font
					(size 1.27 1.27)
					(thickness 0.15)
				)
				(justify left bottom)
				(hide yes)
			)
		)
		(property "Description" "Power Inductors - SMD WE-MAPI 1.8uH 4.6A DCR=30mOhms AEC-Q200"
			(at 327.66 77.47 0)
			(effects
				(font
					(size 1.27 1.27)
				)
				(hide yes)
			)
		)
		(property "Val" "1u8/6.8A"
			(at 330.2 74.93 0)
			(effects
				(font
					(size 1.27 1.27)
					(thickness 0.15)
				)
			)
		)
		(property "Manufacturer" "Würth Elektronik"
			(at 341.63 90.17 0)
			(effects
				(font
					(size 1.27 1.27)
					(thickness 0.15)
				)
				(justify left bottom)
				(hide yes)
			)
		)
		(property "MPN" "74438356018"
			(at 341.63 92.71 0)
			(effects
				(font
					(size 1.27 1.27)
					(thickness 0.15)
				)
				(justify left bottom)
				(hide yes)
			)
		)
		(property "ISat" "6.5 A"
			(at 341.63 93.98 0)
			(effects
				(font
					(size 1.27 1.27)
				)
				(justify left)
				(hide yes)
			)
		)
		(property "IMax" "6.8 A"
			(at 341.63 97.79 0)
			(effects
				(font
					(size 1.27 1.27)
					(thickness 0.15)
				)
				(justify left bottom)
				(hide yes)
			)
		)
		(property "Size" "4.1x4.1mm"
			(at 341.63 100.33 0)
			(effects
				(font
					(size 1.27 1.27)
					(thickness 0.15)
				)
				(justify left bottom)
				(hide yes)
			)
		)
		(property "Author" "Antmicro"
			(at 341.63 102.87 0)
			(effects
				(font
					(size 1.27 1.27)
					(thickness 0.15)
				)
				(justify left bottom)
				(hide yes)
			)
		)
		(property "License" "Apache-2.0"
			(at 341.63 105.41 0)
			(effects
				(font
					(size 1.27 1.27)
					(thickness 0.15)
				)
				(justify left bottom)
				(hide yes)
			)
		)
		(pin "2"
		)
		(pin "1"
		)
		(instances
			(project ""
				(path ""
					(reference "L1")
					(unit 1)
				)
			)
		)
	)
	(symbol
		(lib_id "antmicropower:GND")
		(at 334.01 227.33 0)
		(mirror y)
		(unit 1)
		(exclude_from_sim no)
		(in_bom yes)
		(on_board yes)
		(dnp no)
		(property "Reference" "#PWR067"
			(at 325.12 229.87 0)
			(effects
				(font
					(size 1.27 1.27)
					(thickness 0.15)
				)
				(justify left bottom)
				(hide yes)
			)
		)
		(property "Value" "GND"
			(at 334.01 231.14 0)
			(effects
				(font
					(size 1.27 1.27)
					(thickness 0.15)
				)
			)
		)
		(property "Footprint" ""
			(at 325.12 234.95 0)
			(effects
				(font
					(size 1.27 1.27)
					(thickness 0.15)
				)
				(justify left bottom)
				(hide yes)
			)
		)
		(property "Datasheet" ""
			(at 325.12 240.03 0)
			(effects
				(font
					(size 1.27 1.27)
					(thickness 0.15)
				)
				(justify left bottom)
				(hide yes)
			)
		)
		(property "Description" ""
			(at 334.01 227.33 0)
			(effects
				(font
					(size 1.27 1.27)
				)
				(hide yes)
			)
		)
		(property "Author" "Antmicro"
			(at 325.12 234.95 0)
			(effects
				(font
					(size 1.27 1.27)
					(thickness 0.15)
				)
				(justify left bottom)
				(hide yes)
			)
		)
		(property "License" "Apache-2.0"
			(at 325.12 237.49 0)
			(effects
				(font
					(size 1.27 1.27)
					(thickness 0.15)
				)
				(justify left bottom)
				(hide yes)
			)
		)
		(pin "1"
		)
		(instances
			(project "oculink-to-pcie-adapter"
				(path ""
					(reference "#PWR067")
					(unit 1)
				)
			)
		)
	)
	(symbol
		(lib_id "antmicropower:GND")
		(at 233.68 102.87 0)
		(mirror y)
		(unit 1)
		(exclude_from_sim no)
		(in_bom yes)
		(on_board yes)
		(dnp no)
		(fields_autoplaced yes)
		(property "Reference" "#PWR056"
			(at 224.79 105.41 0)
			(effects
				(font
					(size 1.27 1.27)
					(thickness 0.15)
				)
				(justify left bottom)
				(hide yes)
			)
		)
		(property "Value" "GND"
			(at 233.68 106.68 0)
			(effects
				(font
					(size 1.27 1.27)
					(thickness 0.15)
				)
			)
		)
		(property "Footprint" ""
			(at 224.79 110.49 0)
			(effects
				(font
					(size 1.27 1.27)
					(thickness 0.15)
				)
				(justify left bottom)
				(hide yes)
			)
		)
		(property "Datasheet" ""
			(at 224.79 115.57 0)
			(effects
				(font
					(size 1.27 1.27)
					(thickness 0.15)
				)
				(justify left bottom)
				(hide yes)
			)
		)
		(property "Description" ""
			(at 233.68 102.87 0)
			(effects
				(font
					(size 1.27 1.27)
				)
				(hide yes)
			)
		)
		(property "Author" "Antmicro"
			(at 224.79 110.49 0)
			(effects
				(font
					(size 1.27 1.27)
					(thickness 0.15)
				)
				(justify left bottom)
				(hide yes)
			)
		)
		(property "License" "Apache-2.0"
			(at 224.79 113.03 0)
			(effects
				(font
					(size 1.27 1.27)
					(thickness 0.15)
				)
				(justify left bottom)
				(hide yes)
			)
		)
		(pin "1"
		)
		(instances
			(project "oculink-to-pcie-adapter"
				(path ""
					(reference "#PWR056")
					(unit 1)
				)
			)
		)
	)
	(symbol
		(lib_id "antmicroResistors0402:R_15k_0402")
		(at 335.28 95.25 90)
		(unit 1)
		(exclude_from_sim no)
		(in_bom yes)
		(on_board yes)
		(dnp no)
		(property "Reference" "R10"
			(at 336.55 91.44 90)
			(effects
				(font
					(size 1.27 1.27)
					(thickness 0.15)
				)
				(justify right)
			)
		)
		(property "Value" "R_15k_0402"
			(at 347.98 74.93 0)
			(effects
				(font
					(size 1.27 1.27)
					(thickness 0.15)
				)
				(justify left bottom)
				(hide yes)
			)
		)
		(property "Footprint" "antmicro-footprints:R_0402_1005Metric"
			(at 350.52 74.93 0)
			(effects
				(font
					(size 1.27 1.27)
					(thickness 0.15)
				)
				(justify left bottom)
				(hide yes)
			)
		)
		(property "Datasheet" "https://www.bourns.com/docs/product-datasheets/cr.pdf"
			(at 353.06 74.93 0)
			(effects
				(font
					(size 1.27 1.27)
					(thickness 0.15)
				)
				(justify left bottom)
				(hide yes)
			)
		)
		(property "Description" "SMD Chip Resistor, 15 kohm, ± 1%, 62.5 mW, 0402 [1005 Metric], Thick Film, General Purpose"
			(at 335.28 95.25 0)
			(effects
				(font
					(size 1.27 1.27)
				)
				(hide yes)
			)
		)
		(property "MPN" "CR0402-FX-1502GLF"
			(at 355.6 74.93 0)
			(effects
				(font
					(size 1.27 1.27)
					(thickness 0.15)
				)
				(justify left bottom)
				(hide yes)
			)
		)
		(property "Manufacturer" "Bourns"
			(at 358.14 74.93 0)
			(effects
				(font
					(size 1.27 1.27)
					(thickness 0.15)
				)
				(justify left bottom)
				(hide yes)
			)
		)
		(property "License" "Apache-2.0"
			(at 360.68 74.93 0)
			(effects
				(font
					(size 1.27 1.27)
					(thickness 0.15)
				)
				(justify left bottom)
				(hide yes)
			)
		)
		(property "Author" "Antmicro"
			(at 363.22 74.93 0)
			(effects
				(font
					(size 1.27 1.27)
					(thickness 0.15)
				)
				(justify left bottom)
				(hide yes)
			)
		)
		(property "Val" "15k"
			(at 336.55 93.98 90)
			(effects
				(font
					(size 1.27 1.27)
					(thickness 0.15)
				)
				(justify right)
			)
		)
		(property "Tolerance" "1%"
			(at 345.44 74.93 0)
			(effects
				(font
					(size 1.27 1.27)
				)
				(justify left bottom)
				(hide yes)
			)
		)
		(pin "2"
		)
		(pin "1"
		)
		(instances
			(project ""
				(path ""
					(reference "R10")
					(unit 1)
				)
			)
		)
	)
	(symbol
		(lib_id "antmicropower:PWR_FLAG")
		(at 347.98 73.66 0)
		(unit 1)
		(exclude_from_sim no)
		(in_bom yes)
		(on_board yes)
		(dnp no)
		(property "Reference" "#FLG01"
			(at 347.98 71.755 0)
			(effects
				(font
					(size 1.27 1.27)
				)
				(hide yes)
			)
		)
		(property "Value" "PWR_FLAG"
			(at 348.234 69.85 0)
			(effects
				(font
					(size 1.27 1.27)
				)
			)
		)
		(property "Footprint" ""
			(at 347.98 73.66 0)
			(effects
				(font
					(size 1.27 1.27)
				)
				(hide yes)
			)
		)
		(property "Datasheet" ""
			(at 347.98 73.66 0)
			(effects
				(font
					(size 1.27 1.27)
				)
				(hide yes)
			)
		)
		(property "Description" ""
			(at 347.98 73.66 0)
			(effects
				(font
					(size 1.27 1.27)
				)
				(hide yes)
			)
		)
		(pin "1"
		)
		(instances
			(project "oculink-to-pcie-adapter"
				(path ""
					(reference "#FLG01")
					(unit 1)
				)
			)
		)
	)
	(symbol
		(lib_id "antmicropower:GND")
		(at 292.1 233.68 0)
		(mirror y)
		(unit 1)
		(exclude_from_sim no)
		(in_bom yes)
		(on_board yes)
		(dnp no)
		(property "Reference" "#PWR055"
			(at 283.21 236.22 0)
			(effects
				(font
					(size 1.27 1.27)
					(thickness 0.15)
				)
				(justify left bottom)
				(hide yes)
			)
		)
		(property "Value" "GND"
			(at 292.1 237.49 0)
			(effects
				(font
					(size 1.27 1.27)
					(thickness 0.15)
				)
			)
		)
		(property "Footprint" ""
			(at 283.21 241.3 0)
			(effects
				(font
					(size 1.27 1.27)
					(thickness 0.15)
				)
				(justify left bottom)
				(hide yes)
			)
		)
		(property "Datasheet" ""
			(at 283.21 246.38 0)
			(effects
				(font
					(size 1.27 1.27)
					(thickness 0.15)
				)
				(justify left bottom)
				(hide yes)
			)
		)
		(property "Description" ""
			(at 292.1 233.68 0)
			(effects
				(font
					(size 1.27 1.27)
				)
				(hide yes)
			)
		)
		(property "Author" "Antmicro"
			(at 283.21 241.3 0)
			(effects
				(font
					(size 1.27 1.27)
					(thickness 0.15)
				)
				(justify left bottom)
				(hide yes)
			)
		)
		(property "License" "Apache-2.0"
			(at 283.21 243.84 0)
			(effects
				(font
					(size 1.27 1.27)
					(thickness 0.15)
				)
				(justify left bottom)
				(hide yes)
			)
		)
		(pin "1"
		)
		(instances
			(project "oculink-to-pcie-adapter"
				(path ""
					(reference "#PWR055")
					(unit 1)
				)
			)
		)
	)
	(symbol
		(lib_id "antmicroTransistorsFETsMOSFETsSingle:BSS138-7-F")
		(at 284.48 227.33 0)
		(unit 1)
		(exclude_from_sim no)
		(in_bom yes)
		(on_board yes)
		(dnp no)
		(property "Reference" "Q3"
			(at 289.306 230.378 0)
			(effects
				(font
					(size 1.27 1.27)
					(thickness 0.15)
				)
				(justify right)
			)
		)
		(property "Value" "BSS138-7-F"
			(at 307.34 232.41 0)
			(effects
				(font
					(size 1.27 1.27)
					(thickness 0.15)
				)
				(justify left bottom)
				(hide yes)
			)
		)
		(property "Footprint" "antmicro-footprints:SOT-23-3"
			(at 307.34 234.95 0)
			(effects
				(font
					(size 1.27 1.27)
					(thickness 0.15)
				)
				(justify left bottom)
				(hide yes)
			)
		)
		(property "Datasheet" "https://www.diodes.com/assets/Datasheets/ds30144.pdf"
			(at 307.34 237.49 0)
			(effects
				(font
					(size 1.27 1.27)
					(thickness 0.15)
				)
				(justify left bottom)
				(hide yes)
			)
		)
		(property "Description" "Power MOSFET, N Channel, 50 V, 200 mA, 1.4 ohm, SOT-23, Surface Mount"
			(at 344.424 249.174 0)
			(effects
				(font
					(size 1.27 1.27)
				)
				(hide yes)
			)
		)
		(property "MPN" "BSS138-7-F"
			(at 289.306 232.918 0)
			(effects
				(font
					(size 1.27 1.27)
					(thickness 0.15)
				)
				(justify right)
			)
		)
		(property "Manufacturer" "Diodes Incorporated"
			(at 307.34 242.57 0)
			(effects
				(font
					(size 1.27 1.27)
					(thickness 0.15)
				)
				(justify left bottom)
				(hide yes)
			)
		)
		(property "Author" "Antmicro"
			(at 307.34 245.11 0)
			(effects
				(font
					(size 1.27 1.27)
					(thickness 0.15)
				)
				(justify left bottom)
				(hide yes)
			)
		)
		(property "License" "Apache-2.0"
			(at 307.34 247.65 0)
			(effects
				(font
					(size 1.27 1.27)
					(thickness 0.15)
				)
				(justify left bottom)
				(hide yes)
			)
		)
		(pin "2"
		)
		(pin "3"
		)
		(pin "1"
		)
		(instances
			(project "oculink-to-pcie-adapter"
				(path ""
					(reference "Q3")
					(unit 1)
				)
			)
		)
	)
	(symbol
		(lib_id "antmicroResistors0402:R_0R_0402")
		(at 114.3 264.16 0)
		(unit 1)
		(exclude_from_sim no)
		(in_bom yes)
		(on_board yes)
		(dnp yes)
		(property "Reference" "R41"
			(at 113.03 262.89 0)
			(effects
				(font
					(size 1.27 1.27)
					(thickness 0.15)
				)
			)
		)
		(property "Value" "R_0R_0402"
			(at 134.62 276.86 0)
			(effects
				(font
					(size 1.27 1.27)
					(thickness 0.15)
				)
				(justify left bottom)
				(hide yes)
			)
		)
		(property "Footprint" "antmicro-footprints:R_0402_1005Metric"
			(at 134.62 279.4 0)
			(effects
				(font
					(size 1.27 1.27)
					(thickness 0.15)
				)
				(justify left bottom)
				(hide yes)
			)
		)
		(property "Datasheet" "https://industrial.panasonic.com/cdbs/www-data/pdf/RDA0000/AOA0000C301.pdf"
			(at 134.62 281.94 0)
			(effects
				(font
					(size 1.27 1.27)
					(thickness 0.15)
				)
				(justify left bottom)
				(hide yes)
			)
		)
		(property "Description" "SMD Chip Resistor, Jumper, 0 ohm, 100 mW, 0402 [1005 Metric], Thick Film, General Purpose"
			(at 114.3 264.16 0)
			(effects
				(font
					(size 1.27 1.27)
				)
				(hide yes)
			)
		)
		(property "MPN" "ERJ2GE0R00X"
			(at 134.62 284.48 0)
			(effects
				(font
					(size 1.27 1.27)
					(thickness 0.15)
				)
				(justify left bottom)
				(hide yes)
			)
		)
		(property "Manufacturer" "Panasonic"
			(at 134.62 287.02 0)
			(effects
				(font
					(size 1.27 1.27)
					(thickness 0.15)
				)
				(justify left bottom)
				(hide yes)
			)
		)
		(property "License" "Apache-2.0"
			(at 134.62 289.56 0)
			(effects
				(font
					(size 1.27 1.27)
					(thickness 0.15)
				)
				(justify left bottom)
				(hide yes)
			)
		)
		(property "Author" "Antmicro"
			(at 134.62 292.1 0)
			(effects
				(font
					(size 1.27 1.27)
					(thickness 0.15)
				)
				(justify left bottom)
				(hide yes)
			)
		)
		(property "Val" "0R"
			(at 120.65 262.89 0)
			(effects
				(font
					(size 1.27 1.27)
					(thickness 0.15)
				)
			)
		)
		(property "Tolerance" "~"
			(at 134.62 274.32 0)
			(effects
				(font
					(size 1.27 1.27)
				)
				(justify left bottom)
				(hide yes)
			)
		)
		(property "Current" "1A"
			(at 134.62 294.64 0)
			(effects
				(font
					(size 1.27 1.27)
					(thickness 0.15)
				)
				(justify left bottom)
				(hide yes)
			)
		)
		(pin "2"
		)
		(pin "1"
		)
		(instances
			(project "oculink-to-pcie-adapter"
				(path ""
					(reference "R41")
					(unit 1)
				)
			)
		)
	)
	(symbol
		(lib_id "antmicropower:+12V_AON")
		(at 127 64.77 0)
		(unit 1)
		(exclude_from_sim no)
		(in_bom yes)
		(on_board yes)
		(dnp no)
		(property "Reference" "#PWR085"
			(at 127 68.58 0)
			(effects
				(font
					(size 1.27 1.27)
				)
				(hide yes)
			)
		)
		(property "Value" "+12V"
			(at 127 60.96 0)
			(effects
				(font
					(size 1.27 1.27)
				)
			)
		)
		(property "Footprint" ""
			(at 127 64.77 0)
			(effects
				(font
					(size 1.27 1.27)
				)
				(hide yes)
			)
		)
		(property "Datasheet" ""
			(at 127 64.77 0)
			(effects
				(font
					(size 1.27 1.27)
				)
				(hide yes)
			)
		)
		(property "Description" ""
			(at 127 64.77 0)
			(effects
				(font
					(size 1.27 1.27)
				)
				(hide yes)
			)
		)
		(pin "1"
		)
		(instances
			(project "oculink-to-pcie-adapter"
				(path ""
					(reference "#PWR085")
					(unit 1)
				)
			)
		)
	)
	(symbol
		(lib_id "antmicroResistors0402:R_1k5_0402")
		(at 256.54 97.79 90)
		(unit 1)
		(exclude_from_sim no)
		(in_bom yes)
		(on_board yes)
		(dnp no)
		(property "Reference" "R59"
			(at 257.81 93.98 90)
			(effects
				(font
					(size 1.27 1.27)
					(thickness 0.15)
				)
				(justify right)
			)
		)
		(property "Value" "R_1k5_0402"
			(at 269.24 77.47 0)
			(effects
				(font
					(size 1.27 1.27)
					(thickness 0.15)
				)
				(justify left bottom)
				(hide yes)
			)
		)
		(property "Footprint" "antmicro-footprints:R_0402_1005Metric"
			(at 271.78 77.47 0)
			(effects
				(font
					(size 1.27 1.27)
					(thickness 0.15)
				)
				(justify left bottom)
				(hide yes)
			)
		)
		(property "Datasheet" "https://www.bourns.com/docs/product-datasheets/cr.pdf"
			(at 274.32 77.47 0)
			(effects
				(font
					(size 1.27 1.27)
					(thickness 0.15)
				)
				(justify left bottom)
				(hide yes)
			)
		)
		(property "Description" "SMD Chip Resistor, 1.5 kohm, ± 1%, 62.5 mW, 0402 [1005 Metric], Thick Film, General Purpose"
			(at 256.54 97.79 0)
			(effects
				(font
					(size 1.27 1.27)
				)
				(hide yes)
			)
		)
		(property "MPN" "CR0402-FX-1501GLF"
			(at 276.86 77.47 0)
			(effects
				(font
					(size 1.27 1.27)
					(thickness 0.15)
				)
				(justify left bottom)
				(hide yes)
			)
		)
		(property "Manufacturer" "Bourns"
			(at 279.4 77.47 0)
			(effects
				(font
					(size 1.27 1.27)
					(thickness 0.15)
				)
				(justify left bottom)
				(hide yes)
			)
		)
		(property "License" "Apache-2.0"
			(at 281.94 77.47 0)
			(effects
				(font
					(size 1.27 1.27)
					(thickness 0.15)
				)
				(justify left bottom)
				(hide yes)
			)
		)
		(property "Author" "Antmicro"
			(at 284.48 77.47 0)
			(effects
				(font
					(size 1.27 1.27)
					(thickness 0.15)
				)
				(justify left bottom)
				(hide yes)
			)
		)
		(property "Val" "1k5"
			(at 257.81 96.52 90)
			(effects
				(font
					(size 1.27 1.27)
					(thickness 0.15)
				)
				(justify right)
			)
		)
		(property "Tolerance" "1%"
			(at 266.7 77.47 0)
			(effects
				(font
					(size 1.27 1.27)
				)
				(justify left bottom)
				(hide yes)
			)
		)
		(pin "1"
		)
		(pin "2"
		)
		(instances
			(project ""
				(path ""
					(reference "R59")
					(unit 1)
				)
			)
		)
	)
	(symbol
		(lib_id "antmicropower:PWR_FLAG")
		(at 382.27 81.28 270)
		(unit 1)
		(exclude_from_sim no)
		(in_bom yes)
		(on_board yes)
		(dnp no)
		(fields_autoplaced yes)
		(property "Reference" "#FLG08"
			(at 384.175 81.28 0)
			(effects
				(font
					(size 1.27 1.27)
				)
				(hide yes)
			)
		)
		(property "Value" "PWR_FLAG"
			(at 386.08 81.2799 90)
			(effects
				(font
					(size 1.27 1.27)
				)
				(justify left)
			)
		)
		(property "Footprint" ""
			(at 382.27 81.28 0)
			(effects
				(font
					(size 1.27 1.27)
				)
				(hide yes)
			)
		)
		(property "Datasheet" ""
			(at 382.27 81.28 0)
			(effects
				(font
					(size 1.27 1.27)
				)
				(hide yes)
			)
		)
		(property "Description" ""
			(at 382.27 81.28 0)
			(effects
				(font
					(size 1.27 1.27)
				)
				(hide yes)
			)
		)
		(pin "1"
		)
		(instances
			(project "oculink-to-pcie-adapter"
				(path ""
					(reference "#FLG08")
					(unit 1)
				)
			)
		)
	)
	(symbol
		(lib_id "antmicropower:GND")
		(at 335.28 102.87 0)
		(mirror y)
		(unit 1)
		(exclude_from_sim no)
		(in_bom yes)
		(on_board yes)
		(dnp no)
		(fields_autoplaced yes)
		(property "Reference" "#PWR019"
			(at 326.39 105.41 0)
			(effects
				(font
					(size 1.27 1.27)
					(thickness 0.15)
				)
				(justify left bottom)
				(hide yes)
			)
		)
		(property "Value" "GND"
			(at 335.28 106.68 0)
			(effects
				(font
					(size 1.27 1.27)
					(thickness 0.15)
				)
			)
		)
		(property "Footprint" ""
			(at 326.39 110.49 0)
			(effects
				(font
					(size 1.27 1.27)
					(thickness 0.15)
				)
				(justify left bottom)
				(hide yes)
			)
		)
		(property "Datasheet" ""
			(at 326.39 115.57 0)
			(effects
				(font
					(size 1.27 1.27)
					(thickness 0.15)
				)
				(justify left bottom)
				(hide yes)
			)
		)
		(property "Description" ""
			(at 335.28 102.87 0)
			(effects
				(font
					(size 1.27 1.27)
				)
				(hide yes)
			)
		)
		(property "Author" "Antmicro"
			(at 326.39 110.49 0)
			(effects
				(font
					(size 1.27 1.27)
					(thickness 0.15)
				)
				(justify left bottom)
				(hide yes)
			)
		)
		(property "License" "Apache-2.0"
			(at 326.39 113.03 0)
			(effects
				(font
					(size 1.27 1.27)
					(thickness 0.15)
				)
				(justify left bottom)
				(hide yes)
			)
		)
		(pin "1"
		)
		(instances
			(project "oculink-to-pcie-adapter"
				(path ""
					(reference "#PWR019")
					(unit 1)
				)
			)
		)
	)
	(symbol
		(lib_id "antmicroResistors0402:R_68k_0402")
		(at 335.28 85.09 90)
		(unit 1)
		(exclude_from_sim no)
		(in_bom yes)
		(on_board yes)
		(dnp no)
		(property "Reference" "R9"
			(at 336.55 81.28 90)
			(effects
				(font
					(size 1.27 1.27)
					(thickness 0.15)
				)
				(justify right)
			)
		)
		(property "Value" "R_68k_0402"
			(at 347.98 64.77 0)
			(effects
				(font
					(size 1.27 1.27)
					(thickness 0.15)
				)
				(justify left bottom)
				(hide yes)
			)
		)
		(property "Footprint" "antmicro-footprints:R_0402_1005Metric"
			(at 350.52 64.77 0)
			(effects
				(font
					(size 1.27 1.27)
					(thickness 0.15)
				)
				(justify left bottom)
				(hide yes)
			)
		)
		(property "Datasheet" "https://www.bourns.com/docs/product-datasheets/cr.pdf"
			(at 353.06 64.77 0)
			(effects
				(font
					(size 1.27 1.27)
					(thickness 0.15)
				)
				(justify left bottom)
				(hide yes)
			)
		)
		(property "Description" "SMD Chip Resistor"
			(at 335.28 85.09 0)
			(effects
				(font
					(size 1.27 1.27)
				)
				(hide yes)
			)
		)
		(property "MPN" "CR0402-FX-6802GLF"
			(at 355.6 64.77 0)
			(effects
				(font
					(size 1.27 1.27)
					(thickness 0.15)
				)
				(justify left bottom)
				(hide yes)
			)
		)
		(property "Manufacturer" "Bourns"
			(at 358.14 64.77 0)
			(effects
				(font
					(size 1.27 1.27)
					(thickness 0.15)
				)
				(justify left bottom)
				(hide yes)
			)
		)
		(property "License" "Apache-2.0"
			(at 360.68 64.77 0)
			(effects
				(font
					(size 1.27 1.27)
					(thickness 0.15)
				)
				(justify left bottom)
				(hide yes)
			)
		)
		(property "Author" "Antmicro"
			(at 363.22 64.77 0)
			(effects
				(font
					(size 1.27 1.27)
					(thickness 0.15)
				)
				(justify left bottom)
				(hide yes)
			)
		)
		(property "Val" "68k"
			(at 336.55 83.82 90)
			(effects
				(font
					(size 1.27 1.27)
					(thickness 0.15)
				)
				(justify right)
			)
		)
		(property "Tolerance" "1%"
			(at 345.44 64.77 0)
			(effects
				(font
					(size 1.27 1.27)
				)
				(justify left bottom)
				(hide yes)
			)
		)
		(pin "2"
		)
		(pin "1"
		)
		(instances
			(project ""
				(path ""
					(reference "R9")
					(unit 1)
				)
			)
		)
	)
	(symbol
		(lib_id "antmicroTestPoints:TP_Pad0.75mm_Drill0.2mm")
		(at 322.58 195.58 0)
		(unit 1)
		(exclude_from_sim no)
		(in_bom no)
		(on_board yes)
		(dnp no)
		(fields_autoplaced yes)
		(property "Reference" "TP3"
			(at 327.66 195.58 0)
			(effects
				(font
					(size 1.27 1.27)
					(thickness 0.15)
				)
				(justify left)
			)
		)
		(property "Value" "TP_Pad0.75mm_Drill0.2mm"
			(at 332.74 199.39 0)
			(effects
				(font
					(size 1.27 1.27)
					(thickness 0.15)
				)
				(justify left bottom)
				(hide yes)
			)
		)
		(property "Footprint" "antmicro-footprints:TP_Pad0.75mm_Drill0.2mm"
			(at 332.74 201.93 0)
			(effects
				(font
					(size 1.27 1.27)
					(thickness 0.15)
				)
				(justify left bottom)
				(hide yes)
			)
		)
		(property "Datasheet" ""
			(at 340.36 208.28 0)
			(effects
				(font
					(size 1.27 1.27)
					(thickness 0.15)
				)
				(justify left bottom)
				(hide yes)
			)
		)
		(property "Description" "SMT test point"
			(at 322.58 195.58 0)
			(effects
				(font
					(size 1.27 1.27)
				)
				(hide yes)
			)
		)
		(property "MPN" ""
			(at 333.375 207.01 0)
			(effects
				(font
					(size 1.27 1.27)
					(thickness 0.15)
				)
				(justify left bottom)
				(hide yes)
			)
		)
		(property "Manufacturer" ""
			(at 333.375 201.93 0)
			(effects
				(font
					(size 1.27 1.27)
					(thickness 0.15)
				)
				(justify left bottom)
				(hide yes)
			)
		)
		(property "Author" "Antmicro"
			(at 332.74 204.47 0)
			(effects
				(font
					(size 1.27 1.27)
					(thickness 0.15)
				)
				(justify left bottom)
				(hide yes)
			)
		)
		(property "License" "Apache-2.0"
			(at 332.74 207.01 0)
			(effects
				(font
					(size 1.27 1.27)
					(thickness 0.15)
				)
				(justify left bottom)
				(hide yes)
			)
		)
		(pin "1"
		)
		(instances
			(project "oculink-to-pcie-adapter"
				(path ""
					(reference "TP3")
					(unit 1)
				)
			)
		)
	)
	(symbol
		(lib_id "antmicroResistors0402:R_100k_0402")
		(at 132.08 260.35 90)
		(unit 1)
		(exclude_from_sim no)
		(in_bom yes)
		(on_board yes)
		(dnp no)
		(property "Reference" "R7"
			(at 133.35 256.54 90)
			(effects
				(font
					(size 1.27 1.27)
					(thickness 0.15)
				)
				(justify right)
			)
		)
		(property "Value" "R_100k_0402"
			(at 144.78 240.03 0)
			(effects
				(font
					(size 1.27 1.27)
					(thickness 0.15)
				)
				(justify left bottom)
				(hide yes)
			)
		)
		(property "Footprint" "antmicro-footprints:R_0402_1005Metric"
			(at 147.32 240.03 0)
			(effects
				(font
					(size 1.27 1.27)
					(thickness 0.15)
				)
				(justify left bottom)
				(hide yes)
			)
		)
		(property "Datasheet" "https://www.bourns.com/docs/product-datasheets/cr.pdf"
			(at 149.86 240.03 0)
			(effects
				(font
					(size 1.27 1.27)
					(thickness 0.15)
				)
				(justify left bottom)
				(hide yes)
			)
		)
		(property "Description" "SMD Chip Resistor, 100 kohm, ± 1%, 62.5 mW, 0402 [1005 Metric], Thick Film, General Purpose"
			(at 132.08 260.35 0)
			(effects
				(font
					(size 1.27 1.27)
				)
				(hide yes)
			)
		)
		(property "MPN" "CR0402-FX-1003GLF"
			(at 152.4 240.03 0)
			(effects
				(font
					(size 1.27 1.27)
					(thickness 0.15)
				)
				(justify left bottom)
				(hide yes)
			)
		)
		(property "Manufacturer" "Bourns"
			(at 154.94 240.03 0)
			(effects
				(font
					(size 1.27 1.27)
					(thickness 0.15)
				)
				(justify left bottom)
				(hide yes)
			)
		)
		(property "License" "Apache-2.0"
			(at 157.48 240.03 0)
			(effects
				(font
					(size 1.27 1.27)
					(thickness 0.15)
				)
				(justify left bottom)
				(hide yes)
			)
		)
		(property "Author" "Antmicro"
			(at 160.02 240.03 0)
			(effects
				(font
					(size 1.27 1.27)
					(thickness 0.15)
				)
				(justify left bottom)
				(hide yes)
			)
		)
		(property "Val" "100k"
			(at 133.35 259.08 90)
			(effects
				(font
					(size 1.27 1.27)
					(thickness 0.15)
				)
				(justify right)
			)
		)
		(property "Tolerance" "1%"
			(at 142.24 240.03 0)
			(effects
				(font
					(size 1.27 1.27)
				)
				(justify left bottom)
				(hide yes)
			)
		)
		(pin "1"
		)
		(pin "2"
		)
		(instances
			(project ""
				(path ""
					(reference "R7")
					(unit 1)
				)
			)
		)
	)
	(symbol
		(lib_id "antmicroLEDIndicationDiscrete:LED_G_0603_LTST-C190GKT")
		(at 292.1 208.28 90)
		(unit 1)
		(exclude_from_sim no)
		(in_bom yes)
		(on_board yes)
		(dnp no)
		(fields_autoplaced yes)
		(property "Reference" "D2"
			(at 294.64 204.47 90)
			(effects
				(font
					(size 1.27 1.27)
					(thickness 0.15)
				)
				(justify right)
			)
		)
		(property "Value" "LED_G_0603_LTST-C190GKT"
			(at 299.72 185.42 0)
			(effects
				(font
					(size 1.27 1.27)
					(thickness 0.15)
				)
				(justify left bottom)
				(hide yes)
			)
		)
		(property "Footprint" "antmicro-footprints:LED_0603_1608Metric_G"
			(at 302.26 185.42 0)
			(effects
				(font
					(size 1.27 1.27)
					(thickness 0.15)
				)
				(justify left bottom)
				(hide yes)
			)
		)
		(property "Datasheet" "https://media.digikey.com/pdf/Data%20Sheets/Lite-On%20PDFs/LTST-C190GKT.pdf"
			(at 304.8 185.42 0)
			(effects
				(font
					(size 1.27 1.27)
					(thickness 0.15)
				)
				(justify left bottom)
				(hide yes)
			)
		)
		(property "Description" "LED, Green, SMD, 0603, 20 mA, 2.1 V, 569 nm"
			(at 292.1 208.28 0)
			(effects
				(font
					(size 1.27 1.27)
				)
				(hide yes)
			)
		)
		(property "MPN" "LTST-C190GKT"
			(at 307.34 185.42 0)
			(effects
				(font
					(size 1.27 1.27)
					(thickness 0.15)
				)
				(justify left bottom)
				(hide yes)
			)
		)
		(property "Manufacturer" "Lite-On"
			(at 309.88 185.42 0)
			(effects
				(font
					(size 1.27 1.27)
					(thickness 0.15)
				)
				(justify left bottom)
				(hide yes)
			)
		)
		(property "Color" "Green"
			(at 294.64 207.0099 90)
			(effects
				(font
					(size 1.27 1.27)
				)
				(justify right)
			)
		)
		(property "Author" "Antmicro"
			(at 312.42 185.42 0)
			(effects
				(font
					(size 1.27 1.27)
					(thickness 0.15)
				)
				(justify left bottom)
				(hide yes)
			)
		)
		(property "License" "Apache-2.0"
			(at 314.96 185.42 0)
			(effects
				(font
					(size 1.27 1.27)
					(thickness 0.15)
				)
				(justify left bottom)
				(hide yes)
			)
		)
		(pin "2"
		)
		(pin "1"
		)
		(instances
			(project "oculink-to-pcie-adapter"
				(path ""
					(reference "D2")
					(unit 1)
				)
			)
		)
	)
	(symbol
		(lib_id "antmicroFuses:F_7A_1206")
		(at 69.85 118.11 0)
		(unit 1)
		(exclude_from_sim no)
		(in_bom yes)
		(on_board yes)
		(dnp no)
		(fields_autoplaced yes)
		(property "Reference" "F2"
			(at 72.39 113.03 0)
			(effects
				(font
					(size 1.27 1.27)
					(thickness 0.15)
				)
			)
		)
		(property "Value" "F_7A_1206"
			(at 91.44 125.73 0)
			(effects
				(font
					(size 1.27 1.27)
					(thickness 0.15)
				)
				(justify left bottom)
				(hide yes)
			)
		)
		(property "Footprint" "antmicro-footprints:F_1206_3216Metric"
			(at 91.44 128.27 0)
			(effects
				(font
					(size 1.27 1.27)
					(thickness 0.15)
				)
				(justify left bottom)
				(hide yes)
			)
		)
		(property "Datasheet" "https://us.schurter.com/pdf/english/typ_UST_1206.pdf"
			(at 91.44 130.81 0)
			(effects
				(font
					(size 1.27 1.27)
					(thickness 0.15)
				)
				(justify left bottom)
				(hide yes)
			)
		)
		(property "Description" "7 A 32 V AC 63 V DC Fuse Board Mount (Cartridge Style Excluded) Surface Mount 1206 (3216 Metric)"
			(at 69.85 118.11 0)
			(effects
				(font
					(size 1.27 1.27)
				)
				(hide yes)
			)
		)
		(property "Manufacturer" "Schurter"
			(at 91.44 133.35 0)
			(effects
				(font
					(size 1.27 1.27)
					(thickness 0.15)
				)
				(justify left bottom)
				(hide yes)
			)
		)
		(property "MPN" "3413.0326.11"
			(at 72.39 115.57 0)
			(effects
				(font
					(size 1.27 1.27)
					(thickness 0.15)
				)
			)
		)
		(property "Author" "Antmicro"
			(at 91.44 138.43 0)
			(effects
				(font
					(size 1.27 1.27)
					(thickness 0.15)
				)
				(justify left bottom)
				(hide yes)
			)
		)
		(property "License" "Apache-2.0"
			(at 91.44 140.97 0)
			(effects
				(font
					(size 1.27 1.27)
					(thickness 0.15)
				)
				(justify left bottom)
				(hide yes)
			)
		)
		(pin "1"
		)
		(pin "2"
		)
		(instances
			(project "oculink-to-pcie-adapter"
				(path ""
					(reference "F2")
					(unit 1)
				)
			)
		)
	)
	(symbol
		(lib_id "antmicroMechanicalParts:Lightpipe_Mentor_1296.2013")
		(at 335.28 213.36 0)
		(unit 1)
		(exclude_from_sim no)
		(in_bom yes)
		(on_board yes)
		(dnp yes)
		(fields_autoplaced yes)
		(property "Reference" "H1"
			(at 341.63 211.5377 0)
			(effects
				(font
					(size 1.27 1.27)
					(thickness 0.15)
				)
				(justify left)
			)
		)
		(property "Value" "Lightpipe_Mentor_1296.2013"
			(at 341.63 214.0777 0)
			(effects
				(font
					(size 1.27 1.27)
					(thickness 0.15)
				)
				(justify left)
			)
		)
		(property "Footprint" "antmicro-footprints:Mech_Lightpipe_Mentor_1296.2013"
			(at 355.6 220.98 0)
			(effects
				(font
					(size 1.27 1.27)
					(thickness 0.15)
				)
				(justify left bottom)
				(hide yes)
			)
		)
		(property "Datasheet" "https://docs.rs-online.com/e47b/0900766b813f6efb.pdf"
			(at 355.6 223.52 0)
			(effects
				(font
					(size 1.27 1.27)
					(thickness 0.15)
				)
				(justify left bottom)
				(hide yes)
			)
		)
		(property "Description" "Light Pipe, Miniature Triple Line, 14.45 mm, 3 Pipes, Circular, PC Board, Transparent"
			(at 335.28 213.36 0)
			(effects
				(font
					(size 1.27 1.27)
				)
				(hide yes)
			)
		)
		(property "Manufacturer" "Mentor Worldwide"
			(at 355.6 226.06 0)
			(effects
				(font
					(size 1.27 1.27)
					(thickness 0.15)
				)
				(justify left bottom)
				(hide yes)
			)
		)
		(property "MPN" "1296.2013"
			(at 355.6 228.6 0)
			(effects
				(font
					(size 1.27 1.27)
					(thickness 0.15)
				)
				(justify left bottom)
				(hide yes)
			)
		)
		(property "Author" "Antmicro"
			(at 355.6 231.14 0)
			(effects
				(font
					(size 1.27 1.27)
					(thickness 0.15)
				)
				(justify left bottom)
				(hide yes)
			)
		)
		(property "License" "Apache-2.0"
			(at 355.6 233.68 0)
			(effects
				(font
					(size 1.27 1.27)
					(thickness 0.15)
				)
				(justify left bottom)
				(hide yes)
			)
		)
		(instances
			(project ""
				(path ""
					(reference "H1")
					(unit 1)
				)
			)
		)
	)
	(symbol
		(lib_id "antmicropower:GND")
		(at 85.09 242.57 0)
		(mirror y)
		(unit 1)
		(exclude_from_sim no)
		(in_bom yes)
		(on_board yes)
		(dnp no)
		(property "Reference" "#PWR026"
			(at 76.2 245.11 0)
			(effects
				(font
					(size 1.27 1.27)
					(thickness 0.15)
				)
				(justify left bottom)
				(hide yes)
			)
		)
		(property "Value" "GND"
			(at 85.09 246.38 0)
			(effects
				(font
					(size 1.27 1.27)
					(thickness 0.15)
				)
			)
		)
		(property "Footprint" ""
			(at 76.2 250.19 0)
			(effects
				(font
					(size 1.27 1.27)
					(thickness 0.15)
				)
				(justify left bottom)
				(hide yes)
			)
		)
		(property "Datasheet" ""
			(at 76.2 255.27 0)
			(effects
				(font
					(size 1.27 1.27)
					(thickness 0.15)
				)
				(justify left bottom)
				(hide yes)
			)
		)
		(property "Description" ""
			(at 85.09 242.57 0)
			(effects
				(font
					(size 1.27 1.27)
				)
				(hide yes)
			)
		)
		(property "Author" "Antmicro"
			(at 76.2 250.19 0)
			(effects
				(font
					(size 1.27 1.27)
					(thickness 0.15)
				)
				(justify left bottom)
				(hide yes)
			)
		)
		(property "License" "Apache-2.0"
			(at 76.2 252.73 0)
			(effects
				(font
					(size 1.27 1.27)
					(thickness 0.15)
				)
				(justify left bottom)
				(hide yes)
			)
		)
		(pin "1"
		)
		(instances
			(project "oculink-to-pcie-adapter"
				(path ""
					(reference "#PWR026")
					(unit 1)
				)
			)
		)
	)
	(symbol
		(lib_id "antmicroCapacitorspol:C_Pol_150u_30V_Vishay-T59-EE")
		(at 135.89 82.55 270)
		(unit 1)
		(exclude_from_sim no)
		(in_bom yes)
		(on_board yes)
		(dnp no)
		(fields_autoplaced yes)
		(property "Reference" "C29"
			(at 138.43 83.2866 90)
			(effects
				(font
					(size 1.27 1.27)
					(thickness 0.15)
				)
				(justify left)
			)
		)
		(property "Value" "C_Pol_150u_30V_Vishay-T59-EE"
			(at 125.73 97.79 0)
			(effects
				(font
					(size 1.27 1.27)
					(thickness 0.15)
				)
				(justify left bottom)
				(hide yes)
			)
		)
		(property "Footprint" "antmicro-footprints:C_Pol_Vishay-T59-EE"
			(at 123.19 97.79 0)
			(effects
				(font
					(size 1.27 1.27)
					(thickness 0.15)
				)
				(justify left bottom)
				(hide yes)
			)
		)
		(property "Datasheet" "https://www.vishay.com/docs/40191/t59.pdf"
			(at 120.65 97.79 0)
			(effects
				(font
					(size 1.27 1.27)
					(thickness 0.15)
				)
				(justify left bottom)
				(hide yes)
			)
		)
		(property "Description" "Tantalum Capacitors - Polymer 150uF 30volts 20% 75mohms maxESR"
			(at 135.89 82.55 0)
			(effects
				(font
					(size 1.27 1.27)
				)
				(hide yes)
			)
		)
		(property "MPN" "T59EE157M030C0075"
			(at 123.19 96.52 0)
			(effects
				(font
					(size 1.27 1.27)
				)
				(justify left bottom)
				(hide yes)
			)
		)
		(property "Manufacturer" "Vishay"
			(at 118.11 97.79 0)
			(effects
				(font
					(size 1.27 1.27)
					(thickness 0.15)
				)
				(justify left bottom)
				(hide yes)
			)
		)
		(property "Voltage" "30V"
			(at 115.57 97.79 0)
			(effects
				(font
					(size 1.27 1.27)
					(thickness 0.15)
				)
				(justify left bottom)
				(hide yes)
			)
		)
		(property "Val" "150u"
			(at 138.43 85.8266 90)
			(effects
				(font
					(size 1.27 1.27)
					(thickness 0.15)
				)
				(justify left)
			)
		)
		(property "Author" "Antmicro"
			(at 113.03 97.79 0)
			(effects
				(font
					(size 1.27 1.27)
					(thickness 0.15)
				)
				(justify left bottom)
				(hide yes)
			)
		)
		(property "License" "Apache-2.0"
			(at 110.49 97.79 0)
			(effects
				(font
					(size 1.27 1.27)
					(thickness 0.15)
				)
				(justify left bottom)
				(hide yes)
			)
		)
		(property "Dielectric" "template_dielectric"
			(at 110.49 96.52 0)
			(effects
				(font
					(size 1.27 1.27)
				)
				(justify left bottom)
				(hide yes)
			)
		)
		(pin "2"
		)
		(pin "1"
		)
		(instances
			(project "oculink-to-pcie-adapter"
				(path ""
					(reference "C29")
					(unit 1)
				)
			)
		)
	)
	(symbol
		(lib_id "antmicroResistors0402:R_1k_0402")
		(at 292.1 215.9 90)
		(unit 1)
		(exclude_from_sim no)
		(in_bom yes)
		(on_board yes)
		(dnp no)
		(property "Reference" "R42"
			(at 293.37 212.09 90)
			(effects
				(font
					(size 1.27 1.27)
					(thickness 0.15)
				)
				(justify right)
			)
		)
		(property "Value" "R_1k_0402"
			(at 304.8 195.58 0)
			(effects
				(font
					(size 1.27 1.27)
					(thickness 0.15)
				)
				(justify left bottom)
				(hide yes)
			)
		)
		(property "Footprint" "antmicro-footprints:R_0402_1005Metric"
			(at 307.34 195.58 0)
			(effects
				(font
					(size 1.27 1.27)
					(thickness 0.15)
				)
				(justify left bottom)
				(hide yes)
			)
		)
		(property "Datasheet" "https://www.bourns.com/docs/product-datasheets/cr.pdf"
			(at 309.88 195.58 0)
			(effects
				(font
					(size 1.27 1.27)
					(thickness 0.15)
				)
				(justify left bottom)
				(hide yes)
			)
		)
		(property "Description" "SMD Chip Resistor, 1 kohm, ± 1%, 63 mW, 0402 [1005 Metric], Thick Film, General Purpose"
			(at 292.1 215.9 0)
			(effects
				(font
					(size 1.27 1.27)
				)
				(hide yes)
			)
		)
		(property "MPN" "CR0402-FX-1001GLF"
			(at 312.42 195.58 0)
			(effects
				(font
					(size 1.27 1.27)
					(thickness 0.15)
				)
				(justify left bottom)
				(hide yes)
			)
		)
		(property "Manufacturer" "Bourns"
			(at 314.96 195.58 0)
			(effects
				(font
					(size 1.27 1.27)
					(thickness 0.15)
				)
				(justify left bottom)
				(hide yes)
			)
		)
		(property "License" "Apache-2.0"
			(at 317.5 195.58 0)
			(effects
				(font
					(size 1.27 1.27)
					(thickness 0.15)
				)
				(justify left bottom)
				(hide yes)
			)
		)
		(property "Author" "Antmicro"
			(at 320.04 195.58 0)
			(effects
				(font
					(size 1.27 1.27)
					(thickness 0.15)
				)
				(justify left bottom)
				(hide yes)
			)
		)
		(property "Val" "1k"
			(at 293.37 214.63 90)
			(effects
				(font
					(size 1.27 1.27)
					(thickness 0.15)
				)
				(justify right)
			)
		)
		(property "Tolerance" "1%"
			(at 302.26 195.58 0)
			(effects
				(font
					(size 1.27 1.27)
				)
				(justify left bottom)
				(hide yes)
			)
		)
		(pin "2"
		)
		(pin "1"
		)
		(instances
			(project "oculink-to-pcie-adapter"
				(path ""
					(reference "R42")
					(unit 1)
				)
			)
		)
	)
	(symbol
		(lib_id "antmicropower:GND")
		(at 73.66 255.27 0)
		(mirror y)
		(unit 1)
		(exclude_from_sim no)
		(in_bom yes)
		(on_board yes)
		(dnp no)
		(property "Reference" "#PWR023"
			(at 64.77 257.81 0)
			(effects
				(font
					(size 1.27 1.27)
					(thickness 0.15)
				)
				(justify left bottom)
				(hide yes)
			)
		)
		(property "Value" "GND"
			(at 73.66 259.08 0)
			(effects
				(font
					(size 1.27 1.27)
					(thickness 0.15)
				)
			)
		)
		(property "Footprint" ""
			(at 64.77 262.89 0)
			(effects
				(font
					(size 1.27 1.27)
					(thickness 0.15)
				)
				(justify left bottom)
				(hide yes)
			)
		)
		(property "Datasheet" ""
			(at 64.77 267.97 0)
			(effects
				(font
					(size 1.27 1.27)
					(thickness 0.15)
				)
				(justify left bottom)
				(hide yes)
			)
		)
		(property "Description" ""
			(at 73.66 255.27 0)
			(effects
				(font
					(size 1.27 1.27)
				)
				(hide yes)
			)
		)
		(property "Author" "Antmicro"
			(at 64.77 262.89 0)
			(effects
				(font
					(size 1.27 1.27)
					(thickness 0.15)
				)
				(justify left bottom)
				(hide yes)
			)
		)
		(property "License" "Apache-2.0"
			(at 64.77 265.43 0)
			(effects
				(font
					(size 1.27 1.27)
					(thickness 0.15)
				)
				(justify left bottom)
				(hide yes)
			)
		)
		(pin "1"
		)
		(instances
			(project "oculink-to-pcie-adapter"
				(path ""
					(reference "#PWR023")
					(unit 1)
				)
			)
		)
	)
	(symbol
		(lib_id "antmicropower:+12V_AON")
		(at 304.8 190.5 0)
		(unit 1)
		(exclude_from_sim no)
		(in_bom yes)
		(on_board yes)
		(dnp no)
		(property "Reference" "#PWR022"
			(at 304.8 194.31 0)
			(effects
				(font
					(size 1.27 1.27)
				)
				(hide yes)
			)
		)
		(property "Value" "+12V"
			(at 304.8 186.69 0)
			(effects
				(font
					(size 1.27 1.27)
				)
			)
		)
		(property "Footprint" ""
			(at 304.8 190.5 0)
			(effects
				(font
					(size 1.27 1.27)
				)
				(hide yes)
			)
		)
		(property "Datasheet" ""
			(at 304.8 190.5 0)
			(effects
				(font
					(size 1.27 1.27)
				)
				(hide yes)
			)
		)
		(property "Description" ""
			(at 304.8 190.5 0)
			(effects
				(font
					(size 1.27 1.27)
				)
				(hide yes)
			)
		)
		(pin "1"
		)
		(instances
			(project "oculink-to-pcie-adapter"
				(path ""
					(reference "#PWR022")
					(unit 1)
				)
			)
		)
	)
	(symbol
		(lib_id "antmicropower:GND")
		(at 317.5 233.68 0)
		(mirror y)
		(unit 1)
		(exclude_from_sim no)
		(in_bom yes)
		(on_board yes)
		(dnp no)
		(property "Reference" "#PWR029"
			(at 308.61 236.22 0)
			(effects
				(font
					(size 1.27 1.27)
					(thickness 0.15)
				)
				(justify left bottom)
				(hide yes)
			)
		)
		(property "Value" "GND"
			(at 317.5 237.49 0)
			(effects
				(font
					(size 1.27 1.27)
					(thickness 0.15)
				)
			)
		)
		(property "Footprint" ""
			(at 308.61 241.3 0)
			(effects
				(font
					(size 1.27 1.27)
					(thickness 0.15)
				)
				(justify left bottom)
				(hide yes)
			)
		)
		(property "Datasheet" ""
			(at 308.61 246.38 0)
			(effects
				(font
					(size 1.27 1.27)
					(thickness 0.15)
				)
				(justify left bottom)
				(hide yes)
			)
		)
		(property "Description" ""
			(at 317.5 233.68 0)
			(effects
				(font
					(size 1.27 1.27)
				)
				(hide yes)
			)
		)
		(property "Author" "Antmicro"
			(at 308.61 241.3 0)
			(effects
				(font
					(size 1.27 1.27)
					(thickness 0.15)
				)
				(justify left bottom)
				(hide yes)
			)
		)
		(property "License" "Apache-2.0"
			(at 308.61 243.84 0)
			(effects
				(font
					(size 1.27 1.27)
					(thickness 0.15)
				)
				(justify left bottom)
				(hide yes)
			)
		)
		(pin "1"
		)
		(instances
			(project "oculink-to-pcie-adapter"
				(path ""
					(reference "#PWR029")
					(unit 1)
				)
			)
		)
	)
	(symbol
		(lib_id "antmicropower:+12V_AON")
		(at 223.52 69.85 0)
		(unit 1)
		(exclude_from_sim no)
		(in_bom yes)
		(on_board yes)
		(dnp no)
		(property "Reference" "#PWR011"
			(at 223.52 73.66 0)
			(effects
				(font
					(size 1.27 1.27)
				)
				(hide yes)
			)
		)
		(property "Value" "+12V"
			(at 223.52 66.04 0)
			(effects
				(font
					(size 1.27 1.27)
				)
			)
		)
		(property "Footprint" ""
			(at 223.52 69.85 0)
			(effects
				(font
					(size 1.27 1.27)
				)
				(hide yes)
			)
		)
		(property "Datasheet" ""
			(at 223.52 69.85 0)
			(effects
				(font
					(size 1.27 1.27)
				)
				(hide yes)
			)
		)
		(property "Description" ""
			(at 223.52 69.85 0)
			(effects
				(font
					(size 1.27 1.27)
				)
				(hide yes)
			)
		)
		(pin "1"
		)
		(instances
			(project "oculink-to-pcie-adapter"
				(path ""
					(reference "#PWR011")
					(unit 1)
				)
			)
		)
	)
	(symbol
		(lib_id "antmicropower:+3V3")
		(at 85.09 234.95 0)
		(unit 1)
		(exclude_from_sim no)
		(in_bom yes)
		(on_board yes)
		(dnp no)
		(property "Reference" "#PWR025"
			(at 100.33 234.95 0)
			(effects
				(font
					(size 1.27 1.27)
					(thickness 0.15)
				)
				(justify left bottom)
				(hide yes)
			)
		)
		(property "Value" "+3V3"
			(at 85.09 231.14 0)
			(effects
				(font
					(size 1.27 1.27)
					(thickness 0.15)
				)
			)
		)
		(property "Footprint" ""
			(at 100.33 242.57 0)
			(effects
				(font
					(size 1.27 1.27)
					(thickness 0.15)
				)
				(justify left bottom)
				(hide yes)
			)
		)
		(property "Datasheet" ""
			(at 100.33 245.11 0)
			(effects
				(font
					(size 1.27 1.27)
					(thickness 0.15)
				)
				(justify left bottom)
				(hide yes)
			)
		)
		(property "Description" ""
			(at 85.09 234.95 0)
			(effects
				(font
					(size 1.27 1.27)
				)
				(hide yes)
			)
		)
		(property "Author" "Antmicro"
			(at 100.33 237.49 0)
			(effects
				(font
					(size 1.27 1.27)
					(thickness 0.15)
				)
				(justify left bottom)
				(hide yes)
			)
		)
		(property "License" "Apache-2.0"
			(at 100.33 240.03 0)
			(effects
				(font
					(size 1.27 1.27)
					(thickness 0.15)
				)
				(justify left bottom)
				(hide yes)
			)
		)
		(pin "1"
		)
		(instances
			(project "oculink-to-pcie-adapter"
				(path ""
					(reference "#PWR025")
					(unit 1)
				)
			)
		)
	)
	(symbol
		(lib_id "antmicropower:+3V3")
		(at 292.1 190.5 0)
		(unit 1)
		(exclude_from_sim no)
		(in_bom yes)
		(on_board yes)
		(dnp no)
		(property "Reference" "#PWR040"
			(at 307.34 190.5 0)
			(effects
				(font
					(size 1.27 1.27)
					(thickness 0.15)
				)
				(justify left bottom)
				(hide yes)
			)
		)
		(property "Value" "+3V3"
			(at 292.1 186.69 0)
			(effects
				(font
					(size 1.27 1.27)
					(thickness 0.15)
				)
			)
		)
		(property "Footprint" ""
			(at 307.34 198.12 0)
			(effects
				(font
					(size 1.27 1.27)
					(thickness 0.15)
				)
				(justify left bottom)
				(hide yes)
			)
		)
		(property "Datasheet" ""
			(at 307.34 200.66 0)
			(effects
				(font
					(size 1.27 1.27)
					(thickness 0.15)
				)
				(justify left bottom)
				(hide yes)
			)
		)
		(property "Description" ""
			(at 292.1 190.5 0)
			(effects
				(font
					(size 1.27 1.27)
				)
				(hide yes)
			)
		)
		(property "Author" "Antmicro"
			(at 307.34 193.04 0)
			(effects
				(font
					(size 1.27 1.27)
					(thickness 0.15)
				)
				(justify left bottom)
				(hide yes)
			)
		)
		(property "License" "Apache-2.0"
			(at 307.34 195.58 0)
			(effects
				(font
					(size 1.27 1.27)
					(thickness 0.15)
				)
				(justify left bottom)
				(hide yes)
			)
		)
		(pin "1"
		)
		(instances
			(project "oculink-to-pcie-adapter"
				(path ""
					(reference "#PWR040")
					(unit 1)
				)
			)
		)
	)
	(symbol
		(lib_id "antmicroResistors0402:R_10k_0402")
		(at 304.8 215.9 90)
		(unit 1)
		(exclude_from_sim no)
		(in_bom yes)
		(on_board yes)
		(dnp no)
		(property "Reference" "R12"
			(at 306.07 212.344 90)
			(effects
				(font
					(size 1.27 1.27)
					(thickness 0.15)
				)
				(justify right)
			)
		)
		(property "Value" "R_10k_0402"
			(at 317.5 195.58 0)
			(effects
				(font
					(size 1.27 1.27)
					(thickness 0.15)
				)
				(justify left bottom)
				(hide yes)
			)
		)
		(property "Footprint" "antmicro-footprints:R_0402_1005Metric"
			(at 320.04 195.58 0)
			(effects
				(font
					(size 1.27 1.27)
					(thickness 0.15)
				)
				(justify left bottom)
				(hide yes)
			)
		)
		(property "Datasheet" "https://www.bourns.com/docs/product-datasheets/cr.pdf"
			(at 322.58 195.58 0)
			(effects
				(font
					(size 1.27 1.27)
					(thickness 0.15)
				)
				(justify left bottom)
				(hide yes)
			)
		)
		(property "Description" "SMD Chip Resistor, 10 kohm, ± 1%, 62.5 mW, 0402 [1005 Metric], Thick Film, General Purpose"
			(at 304.8 215.9 0)
			(effects
				(font
					(size 1.27 1.27)
				)
				(hide yes)
			)
		)
		(property "MPN" "CR0402-FX-1002GLF"
			(at 325.12 195.58 0)
			(effects
				(font
					(size 1.27 1.27)
					(thickness 0.15)
				)
				(justify left bottom)
				(hide yes)
			)
		)
		(property "Manufacturer" "Bourns"
			(at 327.66 195.58 0)
			(effects
				(font
					(size 1.27 1.27)
					(thickness 0.15)
				)
				(justify left bottom)
				(hide yes)
			)
		)
		(property "License" "Apache-2.0"
			(at 330.2 195.58 0)
			(effects
				(font
					(size 1.27 1.27)
					(thickness 0.15)
				)
				(justify left bottom)
				(hide yes)
			)
		)
		(property "Author" "Antmicro"
			(at 332.74 195.58 0)
			(effects
				(font
					(size 1.27 1.27)
					(thickness 0.15)
				)
				(justify left bottom)
				(hide yes)
			)
		)
		(property "Val" "10k"
			(at 306.07 214.884 90)
			(effects
				(font
					(size 1.27 1.27)
					(thickness 0.15)
				)
				(justify right)
			)
		)
		(property "Tolerance" "1%"
			(at 314.96 195.58 0)
			(effects
				(font
					(size 1.27 1.27)
				)
				(justify left bottom)
				(hide yes)
			)
		)
		(pin "2"
		)
		(pin "1"
		)
		(instances
			(project "oculink-to-pcie-adapter"
				(path ""
					(reference "R12")
					(unit 1)
				)
			)
		)
	)
	(symbol
		(lib_id "antmicroTestPoints:TP_Pad0.75mm_Drill0.2mm")
		(at 322.58 198.12 0)
		(unit 1)
		(exclude_from_sim no)
		(in_bom no)
		(on_board yes)
		(dnp no)
		(fields_autoplaced yes)
		(property "Reference" "TP2"
			(at 327.66 198.12 0)
			(effects
				(font
					(size 1.27 1.27)
					(thickness 0.15)
				)
				(justify left)
			)
		)
		(property "Value" "TP_Pad0.75mm_Drill0.2mm"
			(at 332.74 201.93 0)
			(effects
				(font
					(size 1.27 1.27)
					(thickness 0.15)
				)
				(justify left bottom)
				(hide yes)
			)
		)
		(property "Footprint" "antmicro-footprints:TP_Pad0.75mm_Drill0.2mm"
			(at 332.74 204.47 0)
			(effects
				(font
					(size 1.27 1.27)
					(thickness 0.15)
				)
				(justify left bottom)
				(hide yes)
			)
		)
		(property "Datasheet" ""
			(at 340.36 210.82 0)
			(effects
				(font
					(size 1.27 1.27)
					(thickness 0.15)
				)
				(justify left bottom)
				(hide yes)
			)
		)
		(property "Description" "SMT test point"
			(at 322.58 198.12 0)
			(effects
				(font
					(size 1.27 1.27)
				)
				(hide yes)
			)
		)
		(property "MPN" ""
			(at 333.375 209.55 0)
			(effects
				(font
					(size 1.27 1.27)
					(thickness 0.15)
				)
				(justify left bottom)
				(hide yes)
			)
		)
		(property "Manufacturer" ""
			(at 333.375 204.47 0)
			(effects
				(font
					(size 1.27 1.27)
					(thickness 0.15)
				)
				(justify left bottom)
				(hide yes)
			)
		)
		(property "Author" "Antmicro"
			(at 332.74 207.01 0)
			(effects
				(font
					(size 1.27 1.27)
					(thickness 0.15)
				)
				(justify left bottom)
				(hide yes)
			)
		)
		(property "License" "Apache-2.0"
			(at 332.74 209.55 0)
			(effects
				(font
					(size 1.27 1.27)
					(thickness 0.15)
				)
				(justify left bottom)
				(hide yes)
			)
		)
		(pin "1"
		)
		(instances
			(project "oculink-to-pcie-adapter"
				(path ""
					(reference "TP2")
					(unit 1)
				)
			)
		)
	)
	(symbol
		(lib_id "antmicroResistors0402:R_10k_0402")
		(at 292.1 83.82 270)
		(unit 1)
		(exclude_from_sim no)
		(in_bom yes)
		(on_board yes)
		(dnp no)
		(property "Reference" "R6"
			(at 290.83 85.09 90)
			(effects
				(font
					(size 1.27 1.27)
					(thickness 0.15)
				)
				(justify right)
			)
		)
		(property "Value" "R_10k_0402"
			(at 279.4 104.14 0)
			(effects
				(font
					(size 1.27 1.27)
					(thickness 0.15)
				)
				(justify left bottom)
				(hide yes)
			)
		)
		(property "Footprint" "antmicro-footprints:R_0402_1005Metric"
			(at 276.86 104.14 0)
			(effects
				(font
					(size 1.27 1.27)
					(thickness 0.15)
				)
				(justify left bottom)
				(hide yes)
			)
		)
		(property "Datasheet" "https://www.bourns.com/docs/product-datasheets/cr.pdf"
			(at 274.32 104.14 0)
			(effects
				(font
					(size 1.27 1.27)
					(thickness 0.15)
				)
				(justify left bottom)
				(hide yes)
			)
		)
		(property "Description" "SMD Chip Resistor, 10 kohm, ± 1%, 62.5 mW, 0402 [1005 Metric], Thick Film, General Purpose"
			(at 292.1 83.82 0)
			(effects
				(font
					(size 1.27 1.27)
				)
				(hide yes)
			)
		)
		(property "MPN" "CR0402-FX-1002GLF"
			(at 271.78 104.14 0)
			(effects
				(font
					(size 1.27 1.27)
					(thickness 0.15)
				)
				(justify left bottom)
				(hide yes)
			)
		)
		(property "Manufacturer" "Bourns"
			(at 269.24 104.14 0)
			(effects
				(font
					(size 1.27 1.27)
					(thickness 0.15)
				)
				(justify left bottom)
				(hide yes)
			)
		)
		(property "License" "Apache-2.0"
			(at 266.7 104.14 0)
			(effects
				(font
					(size 1.27 1.27)
					(thickness 0.15)
				)
				(justify left bottom)
				(hide yes)
			)
		)
		(property "Author" "Antmicro"
			(at 264.16 104.14 0)
			(effects
				(font
					(size 1.27 1.27)
					(thickness 0.15)
				)
				(justify left bottom)
				(hide yes)
			)
		)
		(property "Val" "10k"
			(at 290.83 87.63 90)
			(effects
				(font
					(size 1.27 1.27)
					(thickness 0.15)
				)
				(justify right)
			)
		)
		(property "Tolerance" "1%"
			(at 281.94 104.14 0)
			(effects
				(font
					(size 1.27 1.27)
				)
				(justify left bottom)
				(hide yes)
			)
		)
		(pin "1"
		)
		(pin "2"
		)
		(instances
			(project "oculink-to-pcie-adapter"
				(path ""
					(reference "R6")
					(unit 1)
				)
			)
		)
	)
	(symbol
		(lib_id "antmicroResistors0402:R_10k_0402")
		(at 248.92 77.47 0)
		(unit 1)
		(exclude_from_sim no)
		(in_bom yes)
		(on_board yes)
		(dnp no)
		(property "Reference" "R54"
			(at 251.46 75.565 0)
			(effects
				(font
					(size 1.27 1.27)
					(thickness 0.15)
				)
			)
		)
		(property "Value" "R_10k_0402"
			(at 269.24 90.17 0)
			(effects
				(font
					(size 1.27 1.27)
					(thickness 0.15)
				)
				(justify left bottom)
				(hide yes)
			)
		)
		(property "Footprint" "antmicro-footprints:R_0402_1005Metric"
			(at 269.24 92.71 0)
			(effects
				(font
					(size 1.27 1.27)
					(thickness 0.15)
				)
				(justify left bottom)
				(hide yes)
			)
		)
		(property "Datasheet" "https://www.bourns.com/docs/product-datasheets/cr.pdf"
			(at 269.24 95.25 0)
			(effects
				(font
					(size 1.27 1.27)
					(thickness 0.15)
				)
				(justify left bottom)
				(hide yes)
			)
		)
		(property "Description" "SMD Chip Resistor, 10 kohm, ± 1%, 62.5 mW, 0402 [1005 Metric], Thick Film, General Purpose"
			(at 248.92 77.47 0)
			(effects
				(font
					(size 1.27 1.27)
				)
				(hide yes)
			)
		)
		(property "MPN" "CR0402-FX-1002GLF"
			(at 269.24 97.79 0)
			(effects
				(font
					(size 1.27 1.27)
					(thickness 0.15)
				)
				(justify left bottom)
				(hide yes)
			)
		)
		(property "Manufacturer" "Bourns"
			(at 269.24 100.33 0)
			(effects
				(font
					(size 1.27 1.27)
					(thickness 0.15)
				)
				(justify left bottom)
				(hide yes)
			)
		)
		(property "License" "Apache-2.0"
			(at 269.24 102.87 0)
			(effects
				(font
					(size 1.27 1.27)
					(thickness 0.15)
				)
				(justify left bottom)
				(hide yes)
			)
		)
		(property "Author" "Antmicro"
			(at 269.24 105.41 0)
			(effects
				(font
					(size 1.27 1.27)
					(thickness 0.15)
				)
				(justify left bottom)
				(hide yes)
			)
		)
		(property "Val" "10k"
			(at 251.46 79.375 0)
			(effects
				(font
					(size 1.27 1.27)
					(thickness 0.15)
				)
			)
		)
		(property "Tolerance" "1%"
			(at 269.24 87.63 0)
			(effects
				(font
					(size 1.27 1.27)
				)
				(justify left bottom)
				(hide yes)
			)
		)
		(pin "2"
		)
		(pin "1"
		)
		(instances
			(project ""
				(path ""
					(reference "R54")
					(unit 1)
				)
			)
		)
	)
	(symbol
		(lib_id "antmicropower:+3V3")
		(at 317.5 190.5 0)
		(unit 1)
		(exclude_from_sim no)
		(in_bom yes)
		(on_board yes)
		(dnp no)
		(property "Reference" "#PWR024"
			(at 332.74 190.5 0)
			(effects
				(font
					(size 1.27 1.27)
					(thickness 0.15)
				)
				(justify left bottom)
				(hide yes)
			)
		)
		(property "Value" "+3V3"
			(at 317.5 186.69 0)
			(effects
				(font
					(size 1.27 1.27)
					(thickness 0.15)
				)
			)
		)
		(property "Footprint" ""
			(at 332.74 198.12 0)
			(effects
				(font
					(size 1.27 1.27)
					(thickness 0.15)
				)
				(justify left bottom)
				(hide yes)
			)
		)
		(property "Datasheet" ""
			(at 332.74 200.66 0)
			(effects
				(font
					(size 1.27 1.27)
					(thickness 0.15)
				)
				(justify left bottom)
				(hide yes)
			)
		)
		(property "Description" ""
			(at 317.5 190.5 0)
			(effects
				(font
					(size 1.27 1.27)
				)
				(hide yes)
			)
		)
		(property "Author" "Antmicro"
			(at 332.74 193.04 0)
			(effects
				(font
					(size 1.27 1.27)
					(thickness 0.15)
				)
				(justify left bottom)
				(hide yes)
			)
		)
		(property "License" "Apache-2.0"
			(at 332.74 195.58 0)
			(effects
				(font
					(size 1.27 1.27)
					(thickness 0.15)
				)
				(justify left bottom)
				(hide yes)
			)
		)
		(pin "1"
		)
		(instances
			(project "oculink-to-pcie-adapter"
				(path ""
					(reference "#PWR024")
					(unit 1)
				)
			)
		)
	)
	(symbol
		(lib_id "antmicropower:PWR_FLAG")
		(at 88.9 115.57 0)
		(unit 1)
		(exclude_from_sim no)
		(in_bom yes)
		(on_board yes)
		(dnp no)
		(property "Reference" "#FLG03"
			(at 88.9 113.665 0)
			(effects
				(font
					(size 1.27 1.27)
				)
				(hide yes)
			)
		)
		(property "Value" "PWR_FLAG"
			(at 88.9 111.76 0)
			(effects
				(font
					(size 1.27 1.27)
				)
			)
		)
		(property "Footprint" ""
			(at 88.9 115.57 0)
			(effects
				(font
					(size 1.27 1.27)
				)
				(hide yes)
			)
		)
		(property "Datasheet" ""
			(at 88.9 115.57 0)
			(effects
				(font
					(size 1.27 1.27)
				)
				(hide yes)
			)
		)
		(property "Description" ""
			(at 88.9 115.57 0)
			(effects
				(font
					(size 1.27 1.27)
				)
				(hide yes)
			)
		)
		(pin "1"
		)
		(instances
			(project "oculink-to-pcie-adapter"
				(path ""
					(reference "#FLG03")
					(unit 1)
				)
			)
		)
	)
	(symbol
		(lib_id "antmicropower:GND")
		(at 361.95 102.87 0)
		(unit 1)
		(exclude_from_sim no)
		(in_bom yes)
		(on_board yes)
		(dnp no)
		(fields_autoplaced yes)
		(property "Reference" "#PWR021"
			(at 370.84 105.41 0)
			(effects
				(font
					(size 1.27 1.27)
					(thickness 0.15)
				)
				(justify left bottom)
				(hide yes)
			)
		)
		(property "Value" "GND"
			(at 361.95 106.68 0)
			(effects
				(font
					(size 1.27 1.27)
					(thickness 0.15)
				)
			)
		)
		(property "Footprint" ""
			(at 370.84 110.49 0)
			(effects
				(font
					(size 1.27 1.27)
					(thickness 0.15)
				)
				(justify left bottom)
				(hide yes)
			)
		)
		(property "Datasheet" ""
			(at 370.84 115.57 0)
			(effects
				(font
					(size 1.27 1.27)
					(thickness 0.15)
				)
				(justify left bottom)
				(hide yes)
			)
		)
		(property "Description" ""
			(at 361.95 102.87 0)
			(effects
				(font
					(size 1.27 1.27)
				)
				(hide yes)
			)
		)
		(property "Author" "Antmicro"
			(at 370.84 110.49 0)
			(effects
				(font
					(size 1.27 1.27)
					(thickness 0.15)
				)
				(justify left bottom)
				(hide yes)
			)
		)
		(property "License" "Apache-2.0"
			(at 370.84 113.03 0)
			(effects
				(font
					(size 1.27 1.27)
					(thickness 0.15)
				)
				(justify left bottom)
				(hide yes)
			)
		)
		(pin "1"
		)
		(instances
			(project "oculink-to-pcie-adapter"
				(path ""
					(reference "#PWR021")
					(unit 1)
				)
			)
		)
	)
	(symbol
		(lib_id "antmicropower:GND")
		(at 209.55 102.87 0)
		(mirror y)
		(unit 1)
		(exclude_from_sim no)
		(in_bom yes)
		(on_board yes)
		(dnp no)
		(property "Reference" "#PWR086"
			(at 200.66 105.41 0)
			(effects
				(font
					(size 1.27 1.27)
					(thickness 0.15)
				)
				(justify left bottom)
				(hide yes)
			)
		)
		(property "Value" "GND"
			(at 209.55 106.68 0)
			(effects
				(font
					(size 1.27 1.27)
					(thickness 0.15)
				)
			)
		)
		(property "Footprint" ""
			(at 200.66 110.49 0)
			(effects
				(font
					(size 1.27 1.27)
					(thickness 0.15)
				)
				(justify left bottom)
				(hide yes)
			)
		)
		(property "Datasheet" ""
			(at 200.66 115.57 0)
			(effects
				(font
					(size 1.27 1.27)
					(thickness 0.15)
				)
				(justify left bottom)
				(hide yes)
			)
		)
		(property "Description" ""
			(at 209.55 102.87 0)
			(effects
				(font
					(size 1.27 1.27)
				)
				(hide yes)
			)
		)
		(property "Author" "Antmicro"
			(at 200.66 110.49 0)
			(effects
				(font
					(size 1.27 1.27)
					(thickness 0.15)
				)
				(justify left bottom)
				(hide yes)
			)
		)
		(property "License" "Apache-2.0"
			(at 200.66 113.03 0)
			(effects
				(font
					(size 1.27 1.27)
					(thickness 0.15)
				)
				(justify left bottom)
				(hide yes)
			)
		)
		(pin "1"
		)
		(instances
			(project "oculink-to-pcie-adapter"
				(path ""
					(reference "#PWR086")
					(unit 1)
				)
			)
		)
	)
	(symbol
		(lib_id "antmicroCapacitors0402:C_100n_0402")
		(at 85.09 242.57 90)
		(unit 1)
		(exclude_from_sim no)
		(in_bom yes)
		(on_board yes)
		(dnp no)
		(property "Reference" "C12"
			(at 84.455 238.125 90)
			(effects
				(font
					(size 1.27 1.27)
					(thickness 0.15)
				)
				(justify left)
			)
		)
		(property "Value" "C_100n_0402"
			(at 95.25 222.25 0)
			(effects
				(font
					(size 1.27 1.27)
					(thickness 0.15)
				)
				(justify left bottom)
				(hide yes)
			)
		)
		(property "Footprint" "antmicro-footprints:C_0402_1005Metric"
			(at 97.79 222.25 0)
			(effects
				(font
					(size 1.27 1.27)
					(thickness 0.15)
				)
				(justify left bottom)
				(hide yes)
			)
		)
		(property "Datasheet" "https://www.murata.com/products/productdetail?partno=GRM155R61H104KE14%23"
			(at 100.33 222.25 0)
			(effects
				(font
					(size 1.27 1.27)
					(thickness 0.15)
				)
				(justify left bottom)
				(hide yes)
			)
		)
		(property "Description" "SMD Multilayer Ceramic Capacitor, 0.1 µF, 50 V, 0402 [1005 Metric], ± 10%, X5R, GRM Series"
			(at 85.09 242.57 0)
			(effects
				(font
					(size 1.27 1.27)
				)
				(hide yes)
			)
		)
		(property "MPN" "GRM155R61H104KE14D"
			(at 102.87 222.25 0)
			(effects
				(font
					(size 1.27 1.27)
					(thickness 0.15)
				)
				(justify left bottom)
				(hide yes)
			)
		)
		(property "Manufacturer" "Murata"
			(at 105.41 222.25 0)
			(effects
				(font
					(size 1.27 1.27)
					(thickness 0.15)
				)
				(justify left bottom)
				(hide yes)
			)
		)
		(property "License" "Apache-2.0"
			(at 107.95 222.25 0)
			(effects
				(font
					(size 1.27 1.27)
					(thickness 0.15)
				)
				(justify left bottom)
				(hide yes)
			)
		)
		(property "Author" "Antmicro"
			(at 110.49 222.25 0)
			(effects
				(font
					(size 1.27 1.27)
					(thickness 0.15)
				)
				(justify left bottom)
				(hide yes)
			)
		)
		(property "Val" "100n"
			(at 84.455 241.935 90)
			(effects
				(font
					(size 1.27 1.27)
					(thickness 0.15)
				)
				(justify left)
			)
		)
		(property "Voltage" "50V"
			(at 113.03 222.25 0)
			(effects
				(font
					(size 1.27 1.27)
				)
				(justify left bottom)
				(hide yes)
			)
		)
		(property "Dielectric" "X5R"
			(at 115.57 222.25 0)
			(effects
				(font
					(size 1.27 1.27)
				)
				(justify left bottom)
				(hide yes)
			)
		)
		(pin "1"
		)
		(pin "2"
		)
		(instances
			(project ""
				(path ""
					(reference "C12")
					(unit 1)
				)
			)
		)
	)
	(symbol
		(lib_id "antmicropower:GND")
		(at 92.71 213.36 0)
		(mirror y)
		(unit 1)
		(exclude_from_sim no)
		(in_bom yes)
		(on_board yes)
		(dnp no)
		(property "Reference" "#PWR032"
			(at 83.82 215.9 0)
			(effects
				(font
					(size 1.27 1.27)
					(thickness 0.15)
				)
				(justify left bottom)
				(hide yes)
			)
		)
		(property "Value" "GND"
			(at 92.71 217.17 0)
			(effects
				(font
					(size 1.27 1.27)
					(thickness 0.15)
				)
			)
		)
		(property "Footprint" ""
			(at 83.82 220.98 0)
			(effects
				(font
					(size 1.27 1.27)
					(thickness 0.15)
				)
				(justify left bottom)
				(hide yes)
			)
		)
		(property "Datasheet" ""
			(at 83.82 226.06 0)
			(effects
				(font
					(size 1.27 1.27)
					(thickness 0.15)
				)
				(justify left bottom)
				(hide yes)
			)
		)
		(property "Description" ""
			(at 92.71 213.36 0)
			(effects
				(font
					(size 1.27 1.27)
				)
				(hide yes)
			)
		)
		(property "Author" "Antmicro"
			(at 83.82 220.98 0)
			(effects
				(font
					(size 1.27 1.27)
					(thickness 0.15)
				)
				(justify left bottom)
				(hide yes)
			)
		)
		(property "License" "Apache-2.0"
			(at 83.82 223.52 0)
			(effects
				(font
					(size 1.27 1.27)
					(thickness 0.15)
				)
				(justify left bottom)
				(hide yes)
			)
		)
		(pin "1"
		)
		(instances
			(project "oculink-to-pcie-adapter"
				(path ""
					(reference "#PWR032")
					(unit 1)
				)
			)
		)
	)
	(symbol
		(lib_id "antmicropower:PWR_FLAG")
		(at 88.9 90.17 0)
		(unit 1)
		(exclude_from_sim no)
		(in_bom yes)
		(on_board yes)
		(dnp no)
		(property "Reference" "#FLG06"
			(at 88.9 88.265 0)
			(effects
				(font
					(size 1.27 1.27)
				)
				(hide yes)
			)
		)
		(property "Value" "PWR_FLAG"
			(at 88.9 86.36 0)
			(effects
				(font
					(size 1.27 1.27)
				)
			)
		)
		(property "Footprint" ""
			(at 88.9 90.17 0)
			(effects
				(font
					(size 1.27 1.27)
				)
				(hide yes)
			)
		)
		(property "Datasheet" ""
			(at 88.9 90.17 0)
			(effects
				(font
					(size 1.27 1.27)
				)
				(hide yes)
			)
		)
		(property "Description" ""
			(at 88.9 90.17 0)
			(effects
				(font
					(size 1.27 1.27)
				)
				(hide yes)
			)
		)
		(pin "1"
		)
		(instances
			(project "oculink-to-pcie-adapter"
				(path ""
					(reference "#FLG06")
					(unit 1)
				)
			)
		)
	)
	(symbol
		(lib_id "antmicropower:GND")
		(at 313.69 102.87 0)
		(mirror y)
		(unit 1)
		(exclude_from_sim no)
		(in_bom yes)
		(on_board yes)
		(dnp no)
		(fields_autoplaced yes)
		(property "Reference" "#PWR018"
			(at 304.8 105.41 0)
			(effects
				(font
					(size 1.27 1.27)
					(thickness 0.15)
				)
				(justify left bottom)
				(hide yes)
			)
		)
		(property "Value" "GND"
			(at 313.69 106.68 0)
			(effects
				(font
					(size 1.27 1.27)
					(thickness 0.15)
				)
			)
		)
		(property "Footprint" ""
			(at 304.8 110.49 0)
			(effects
				(font
					(size 1.27 1.27)
					(thickness 0.15)
				)
				(justify left bottom)
				(hide yes)
			)
		)
		(property "Datasheet" ""
			(at 304.8 115.57 0)
			(effects
				(font
					(size 1.27 1.27)
					(thickness 0.15)
				)
				(justify left bottom)
				(hide yes)
			)
		)
		(property "Description" ""
			(at 313.69 102.87 0)
			(effects
				(font
					(size 1.27 1.27)
				)
				(hide yes)
			)
		)
		(property "Author" "Antmicro"
			(at 304.8 110.49 0)
			(effects
				(font
					(size 1.27 1.27)
					(thickness 0.15)
				)
				(justify left bottom)
				(hide yes)
			)
		)
		(property "License" "Apache-2.0"
			(at 304.8 113.03 0)
			(effects
				(font
					(size 1.27 1.27)
					(thickness 0.15)
				)
				(justify left bottom)
				(hide yes)
			)
		)
		(pin "1"
		)
		(instances
			(project "oculink-to-pcie-adapter"
				(path ""
					(reference "#PWR018")
					(unit 1)
				)
			)
		)
	)
	(symbol
		(lib_id "antmicropower:GND")
		(at 271.78 102.87 0)
		(mirror y)
		(unit 1)
		(exclude_from_sim no)
		(in_bom yes)
		(on_board yes)
		(dnp no)
		(fields_autoplaced yes)
		(property "Reference" "#PWR017"
			(at 262.89 105.41 0)
			(effects
				(font
					(size 1.27 1.27)
					(thickness 0.15)
				)
				(justify left bottom)
				(hide yes)
			)
		)
		(property "Value" "GND"
			(at 271.78 106.68 0)
			(effects
				(font
					(size 1.27 1.27)
					(thickness 0.15)
				)
			)
		)
		(property "Footprint" ""
			(at 262.89 110.49 0)
			(effects
				(font
					(size 1.27 1.27)
					(thickness 0.15)
				)
				(justify left bottom)
				(hide yes)
			)
		)
		(property "Datasheet" ""
			(at 262.89 115.57 0)
			(effects
				(font
					(size 1.27 1.27)
					(thickness 0.15)
				)
				(justify left bottom)
				(hide yes)
			)
		)
		(property "Description" ""
			(at 271.78 102.87 0)
			(effects
				(font
					(size 1.27 1.27)
				)
				(hide yes)
			)
		)
		(property "Author" "Antmicro"
			(at 262.89 110.49 0)
			(effects
				(font
					(size 1.27 1.27)
					(thickness 0.15)
				)
				(justify left bottom)
				(hide yes)
			)
		)
		(property "License" "Apache-2.0"
			(at 262.89 113.03 0)
			(effects
				(font
					(size 1.27 1.27)
					(thickness 0.15)
				)
				(justify left bottom)
				(hide yes)
			)
		)
		(pin "1"
		)
		(instances
			(project "oculink-to-pcie-adapter"
				(path ""
					(reference "#PWR017")
					(unit 1)
				)
			)
		)
	)
	(symbol
		(lib_id "antmicroLogicGatesandInverters:74AUP2G132")
		(at 92.71 246.38 0)
		(unit 1)
		(exclude_from_sim no)
		(in_bom yes)
		(on_board yes)
		(dnp no)
		(fields_autoplaced yes)
		(property "Reference" "U6"
			(at 101.6 240.03 0)
			(effects
				(font
					(size 1.27 1.27)
					(thickness 0.15)
				)
			)
		)
		(property "Value" "74AUP2G132"
			(at 138.43 256.54 0)
			(effects
				(font
					(size 1.27 1.27)
					(thickness 0.15)
				)
				(justify left bottom)
				(hide yes)
			)
		)
		(property "Footprint" "antmicro-footprints:VSSOP-8_2.3x2mm_P0.5mm"
			(at 138.43 259.08 0)
			(effects
				(font
					(size 1.27 1.27)
					(thickness 0.15)
				)
				(justify left bottom)
				(hide yes)
			)
		)
		(property "Datasheet" "https://assets.nexperia.com/documents/data-sheet/74AUP2G132.pdf"
			(at 138.43 261.62 0)
			(effects
				(font
					(size 1.27 1.27)
					(thickness 0.15)
				)
				(justify left bottom)
				(hide yes)
			)
		)
		(property "Description" "Low-power dual 2-input NAND Schmitt trigger"
			(at 92.71 246.38 0)
			(effects
				(font
					(size 1.27 1.27)
				)
				(hide yes)
			)
		)
		(property "Manufacturer" "Nexperia"
			(at 138.43 264.16 0)
			(effects
				(font
					(size 1.27 1.27)
					(thickness 0.15)
				)
				(justify left bottom)
				(hide yes)
			)
		)
		(property "MPN" "74AUP2G132"
			(at 101.6 242.57 0)
			(effects
				(font
					(size 1.27 1.27)
					(thickness 0.15)
				)
			)
		)
		(property "Author" "Antmicro"
			(at 138.43 266.7 0)
			(effects
				(font
					(size 1.27 1.27)
					(thickness 0.15)
				)
				(justify left bottom)
				(hide yes)
			)
		)
		(property "License" "Apache-2.0"
			(at 138.43 269.24 0)
			(effects
				(font
					(size 1.27 1.27)
					(thickness 0.15)
				)
				(justify left bottom)
				(hide yes)
			)
		)
		(pin "4"
		)
		(pin "1"
		)
		(pin "6"
		)
		(pin "8"
		)
		(pin "5"
		)
		(pin "2"
		)
		(pin "7"
		)
		(pin "3"
		)
		(instances
			(project ""
				(path ""
					(reference "U6")
					(unit 1)
				)
			)
		)
	)
	(symbol
		(lib_id "antmicroResistors0402:R_68k_0402")
		(at 271.78 92.71 90)
		(unit 1)
		(exclude_from_sim no)
		(in_bom no)
		(on_board yes)
		(dnp yes)
		(property "Reference" "R5"
			(at 273.05 88.9 90)
			(effects
				(font
					(size 1.27 1.27)
					(thickness 0.15)
				)
				(justify right)
			)
		)
		(property "Value" "R_68k_0402"
			(at 284.48 72.39 0)
			(effects
				(font
					(size 1.27 1.27)
					(thickness 0.15)
				)
				(justify left bottom)
				(hide yes)
			)
		)
		(property "Footprint" "antmicro-footprints:R_0402_1005Metric"
			(at 287.02 72.39 0)
			(effects
				(font
					(size 1.27 1.27)
					(thickness 0.15)
				)
				(justify left bottom)
				(hide yes)
			)
		)
		(property "Datasheet" "https://www.bourns.com/docs/product-datasheets/cr.pdf"
			(at 289.56 72.39 0)
			(effects
				(font
					(size 1.27 1.27)
					(thickness 0.15)
				)
				(justify left bottom)
				(hide yes)
			)
		)
		(property "Description" "SMD Chip Resistor"
			(at 271.78 92.71 0)
			(effects
				(font
					(size 1.27 1.27)
				)
				(hide yes)
			)
		)
		(property "MPN" "CR0402-FX-6802GLF"
			(at 292.1 72.39 0)
			(effects
				(font
					(size 1.27 1.27)
					(thickness 0.15)
				)
				(justify left bottom)
				(hide yes)
			)
		)
		(property "Manufacturer" "Bourns"
			(at 294.64 72.39 0)
			(effects
				(font
					(size 1.27 1.27)
					(thickness 0.15)
				)
				(justify left bottom)
				(hide yes)
			)
		)
		(property "License" "Apache-2.0"
			(at 297.18 72.39 0)
			(effects
				(font
					(size 1.27 1.27)
					(thickness 0.15)
				)
				(justify left bottom)
				(hide yes)
			)
		)
		(property "Author" "Antmicro"
			(at 299.72 72.39 0)
			(effects
				(font
					(size 1.27 1.27)
					(thickness 0.15)
				)
				(justify left bottom)
				(hide yes)
			)
		)
		(property "Val" "68k"
			(at 273.05 91.44 90)
			(effects
				(font
					(size 1.27 1.27)
					(thickness 0.15)
				)
				(justify right)
			)
		)
		(property "Tolerance" "1%"
			(at 281.94 72.39 0)
			(effects
				(font
					(size 1.27 1.27)
				)
				(justify left bottom)
				(hide yes)
			)
		)
		(pin "2"
		)
		(pin "1"
		)
		(instances
			(project "oculink-to-pcie-adapter"
				(path ""
					(reference "R5")
					(unit 1)
				)
			)
		)
	)
	(symbol
		(lib_id "antmicropower:GND")
		(at 256.54 102.87 0)
		(mirror y)
		(unit 1)
		(exclude_from_sim no)
		(in_bom yes)
		(on_board yes)
		(dnp no)
		(fields_autoplaced yes)
		(property "Reference" "#PWR015"
			(at 247.65 105.41 0)
			(effects
				(font
					(size 1.27 1.27)
					(thickness 0.15)
				)
				(justify left bottom)
				(hide yes)
			)
		)
		(property "Value" "GND"
			(at 256.54 106.68 0)
			(effects
				(font
					(size 1.27 1.27)
					(thickness 0.15)
				)
			)
		)
		(property "Footprint" ""
			(at 247.65 110.49 0)
			(effects
				(font
					(size 1.27 1.27)
					(thickness 0.15)
				)
				(justify left bottom)
				(hide yes)
			)
		)
		(property "Datasheet" ""
			(at 247.65 115.57 0)
			(effects
				(font
					(size 1.27 1.27)
					(thickness 0.15)
				)
				(justify left bottom)
				(hide yes)
			)
		)
		(property "Description" ""
			(at 256.54 102.87 0)
			(effects
				(font
					(size 1.27 1.27)
				)
				(hide yes)
			)
		)
		(property "Author" "Antmicro"
			(at 247.65 110.49 0)
			(effects
				(font
					(size 1.27 1.27)
					(thickness 0.15)
				)
				(justify left bottom)
				(hide yes)
			)
		)
		(property "License" "Apache-2.0"
			(at 247.65 113.03 0)
			(effects
				(font
					(size 1.27 1.27)
					(thickness 0.15)
				)
				(justify left bottom)
				(hide yes)
			)
		)
		(pin "1"
		)
		(instances
			(project "oculink-to-pcie-adapter"
				(path ""
					(reference "#PWR015")
					(unit 1)
				)
			)
		)
	)
	(symbol
		(lib_id "antmicroCapacitors0402:C_100n_0402")
		(at 320.04 72.39 0)
		(unit 1)
		(exclude_from_sim no)
		(in_bom yes)
		(on_board yes)
		(dnp no)
		(fields_autoplaced yes)
		(property "Reference" "C1"
			(at 322.5863 66.04 0)
			(effects
				(font
					(size 1.27 1.27)
					(thickness 0.15)
				)
			)
		)
		(property "Value" "C_100n_0402"
			(at 340.36 82.55 0)
			(effects
				(font
					(size 1.27 1.27)
					(thickness 0.15)
				)
				(justify left bottom)
				(hide yes)
			)
		)
		(property "Footprint" "antmicro-footprints:C_0402_1005Metric"
			(at 340.36 85.09 0)
			(effects
				(font
					(size 1.27 1.27)
					(thickness 0.15)
				)
				(justify left bottom)
				(hide yes)
			)
		)
		(property "Datasheet" "https://www.murata.com/products/productdetail?partno=GRM155R61H104KE14%23"
			(at 340.36 87.63 0)
			(effects
				(font
					(size 1.27 1.27)
					(thickness 0.15)
				)
				(justify left bottom)
				(hide yes)
			)
		)
		(property "Description" "SMD Multilayer Ceramic Capacitor, 0.1 µF, 50 V, 0402 [1005 Metric], ± 10%, X5R, GRM Series"
			(at 320.04 72.39 0)
			(effects
				(font
					(size 1.27 1.27)
				)
				(hide yes)
			)
		)
		(property "MPN" "GRM155R61H104KE14D"
			(at 340.36 90.17 0)
			(effects
				(font
					(size 1.27 1.27)
					(thickness 0.15)
				)
				(justify left bottom)
				(hide yes)
			)
		)
		(property "Manufacturer" "Murata"
			(at 340.36 92.71 0)
			(effects
				(font
					(size 1.27 1.27)
					(thickness 0.15)
				)
				(justify left bottom)
				(hide yes)
			)
		)
		(property "License" "Apache-2.0"
			(at 340.36 95.25 0)
			(effects
				(font
					(size 1.27 1.27)
					(thickness 0.15)
				)
				(justify left bottom)
				(hide yes)
			)
		)
		(property "Author" "Antmicro"
			(at 340.36 97.79 0)
			(effects
				(font
					(size 1.27 1.27)
					(thickness 0.15)
				)
				(justify left bottom)
				(hide yes)
			)
		)
		(property "Val" "100n"
			(at 322.5863 68.58 0)
			(effects
				(font
					(size 1.27 1.27)
					(thickness 0.15)
				)
			)
		)
		(property "Voltage" "50V"
			(at 340.36 100.33 0)
			(effects
				(font
					(size 1.27 1.27)
				)
				(justify left bottom)
				(hide yes)
			)
		)
		(property "Dielectric" "X5R"
			(at 340.36 102.87 0)
			(effects
				(font
					(size 1.27 1.27)
				)
				(justify left bottom)
				(hide yes)
			)
		)
		(pin "1"
		)
		(pin "2"
		)
		(instances
			(project ""
				(path ""
					(reference "C1")
					(unit 1)
				)
			)
		)
	)
	(symbol
		(lib_id "antmicroResistors0402:R_100k_0402")
		(at 73.66 255.27 90)
		(unit 1)
		(exclude_from_sim no)
		(in_bom yes)
		(on_board yes)
		(dnp no)
		(property "Reference" "R8"
			(at 74.93 251.46 90)
			(effects
				(font
					(size 1.27 1.27)
					(thickness 0.15)
				)
				(justify right)
			)
		)
		(property "Value" "R_100k_0402"
			(at 86.36 234.95 0)
			(effects
				(font
					(size 1.27 1.27)
					(thickness 0.15)
				)
				(justify left bottom)
				(hide yes)
			)
		)
		(property "Footprint" "antmicro-footprints:R_0402_1005Metric"
			(at 88.9 234.95 0)
			(effects
				(font
					(size 1.27 1.27)
					(thickness 0.15)
				)
				(justify left bottom)
				(hide yes)
			)
		)
		(property "Datasheet" "https://www.bourns.com/docs/product-datasheets/cr.pdf"
			(at 91.44 234.95 0)
			(effects
				(font
					(size 1.27 1.27)
					(thickness 0.15)
				)
				(justify left bottom)
				(hide yes)
			)
		)
		(property "Description" "SMD Chip Resistor, 100 kohm, ± 1%, 62.5 mW, 0402 [1005 Metric], Thick Film, General Purpose"
			(at 73.66 255.27 0)
			(effects
				(font
					(size 1.27 1.27)
				)
				(hide yes)
			)
		)
		(property "MPN" "CR0402-FX-1003GLF"
			(at 93.98 234.95 0)
			(effects
				(font
					(size 1.27 1.27)
					(thickness 0.15)
				)
				(justify left bottom)
				(hide yes)
			)
		)
		(property "Manufacturer" "Bourns"
			(at 96.52 234.95 0)
			(effects
				(font
					(size 1.27 1.27)
					(thickness 0.15)
				)
				(justify left bottom)
				(hide yes)
			)
		)
		(property "License" "Apache-2.0"
			(at 99.06 234.95 0)
			(effects
				(font
					(size 1.27 1.27)
					(thickness 0.15)
				)
				(justify left bottom)
				(hide yes)
			)
		)
		(property "Author" "Antmicro"
			(at 101.6 234.95 0)
			(effects
				(font
					(size 1.27 1.27)
					(thickness 0.15)
				)
				(justify left bottom)
				(hide yes)
			)
		)
		(property "Val" "100k"
			(at 74.93 254 90)
			(effects
				(font
					(size 1.27 1.27)
					(thickness 0.15)
				)
				(justify right)
			)
		)
		(property "Tolerance" "1%"
			(at 83.82 234.95 0)
			(effects
				(font
					(size 1.27 1.27)
				)
				(justify left bottom)
				(hide yes)
			)
		)
		(pin "2"
		)
		(pin "1"
		)
		(instances
			(project ""
				(path ""
					(reference "R8")
					(unit 1)
				)
			)
		)
	)
	(symbol
		(lib_id "antmicroDCDCConverters:TPS56C230")
		(at 293.37 72.39 0)
		(unit 1)
		(exclude_from_sim no)
		(in_bom yes)
		(on_board yes)
		(dnp no)
		(fields_autoplaced yes)
		(property "Reference" "U1"
			(at 302.26 64.77 0)
			(effects
				(font
					(size 1.27 1.27)
					(thickness 0.15)
				)
			)
		)
		(property "Value" "TPS56C230"
			(at 326.39 77.47 0)
			(effects
				(font
					(size 1.27 1.27)
					(thickness 0.15)
				)
				(justify left bottom)
				(hide yes)
			)
		)
		(property "Footprint" "antmicro-footprints:QFN-20-1EP_3x3mm_P0.45mm"
			(at 326.39 80.01 0)
			(effects
				(font
					(size 1.27 1.27)
					(thickness 0.15)
				)
				(justify left bottom)
				(hide yes)
			)
		)
		(property "Datasheet" "https://www.ti.com/lit/ds/symlink/tps56c230.pdf"
			(at 326.39 82.55 0)
			(effects
				(font
					(size 1.27 1.27)
					(thickness 0.15)
				)
				(justify left bottom)
				(hide yes)
			)
		)
		(property "Description" "DC/DC converter"
			(at 293.37 72.39 0)
			(effects
				(font
					(size 1.27 1.27)
				)
				(hide yes)
			)
		)
		(property "Manufacturer" "Texas Instruments"
			(at 326.39 85.09 0)
			(effects
				(font
					(size 1.27 1.27)
					(thickness 0.15)
				)
				(justify left bottom)
				(hide yes)
			)
		)
		(property "MPN" "TPS56C230RJER"
			(at 302.26 67.31 0)
			(effects
				(font
					(size 1.27 1.27)
					(thickness 0.15)
				)
			)
		)
		(property "Author" "Antmicro"
			(at 326.39 90.17 0)
			(effects
				(font
					(size 1.27 1.27)
					(thickness 0.15)
				)
				(justify left bottom)
				(hide yes)
			)
		)
		(property "License" "Apache-2.0"
			(at 326.39 92.71 0)
			(effects
				(font
					(size 1.27 1.27)
					(thickness 0.15)
				)
				(justify left bottom)
				(hide yes)
			)
		)
		(pin "11"
		)
		(pin "13"
		)
		(pin "7"
		)
		(pin "20"
		)
		(pin "19"
		)
		(pin "14"
		)
		(pin "17"
		)
		(pin "15"
		)
		(pin "8"
		)
		(pin "12"
		)
		(pin "10"
		)
		(pin "16"
		)
		(pin "5"
		)
		(pin "18"
		)
		(pin "21"
		)
		(pin "9"
		)
		(pin "1"
		)
		(pin "4"
		)
		(pin "3"
		)
		(pin "6"
		)
		(pin "2"
		)
		(instances
			(project "oculink-to-pcie-adapter"
				(path ""
					(reference "U1")
					(unit 1)
				)
			)
		)
	)
	(symbol
		(lib_id "antmicropower:GND")
		(at 135.89 88.9 0)
		(unit 1)
		(exclude_from_sim no)
		(in_bom yes)
		(on_board yes)
		(dnp no)
		(property "Reference" "#PWR076"
			(at 135.89 88.9 0)
			(effects
				(font
					(size 1.27 1.27)
				)
				(justify left)
				(hide yes)
			)
		)
		(property "Value" "GND"
			(at 135.89 92.71 0)
			(effects
				(font
					(size 1.27 1.27)
				)
			)
		)
		(property "Footprint" ""
			(at 135.89 88.9 0)
			(effects
				(font
					(size 1.27 1.27)
					(thickness 0.15)
				)
				(justify left bottom)
				(hide yes)
			)
		)
		(property "Datasheet" ""
			(at 135.89 88.9 0)
			(effects
				(font
					(size 1.27 1.27)
					(thickness 0.15)
				)
				(justify left bottom)
				(hide yes)
			)
		)
		(property "Description" ""
			(at 135.89 88.9 0)
			(effects
				(font
					(size 1.27 1.27)
				)
				(hide yes)
			)
		)
		(property "Author" "Antmicro"
			(at 144.78 96.52 0)
			(effects
				(font
					(size 1.27 1.27)
					(thickness 0.15)
				)
				(justify left bottom)
				(hide yes)
			)
		)
		(property "License" "Apache-2.0"
			(at 144.78 99.06 0)
			(effects
				(font
					(size 1.27 1.27)
					(thickness 0.15)
				)
				(justify left bottom)
				(hide yes)
			)
		)
		(pin "1"
		)
		(instances
			(project "oculink-to-pcie-adapter"
				(path ""
					(reference "#PWR076")
					(unit 1)
				)
			)
		)
	)
	(symbol
		(lib_id "antmicroTVSDiodes:SZSMF4L14AT3G")
		(at 85.09 120.65 270)
		(unit 1)
		(exclude_from_sim no)
		(in_bom yes)
		(on_board yes)
		(dnp no)
		(property "Reference" "D8"
			(at 83.566 121.92 90)
			(effects
				(font
					(size 1.27 1.27)
					(thickness 0.15)
				)
				(justify right)
			)
		)
		(property "Value" "SZSMF4L14AT3G"
			(at 74.93 135.89 0)
			(effects
				(font
					(size 1.27 1.27)
					(thickness 0.15)
				)
				(justify left bottom)
				(hide yes)
			)
		)
		(property "Footprint" "antmicro-footprints:SOD-123FL"
			(at 72.39 135.89 0)
			(effects
				(font
					(size 1.27 1.27)
					(thickness 0.15)
				)
				(justify left bottom)
				(hide yes)
			)
		)
		(property "Datasheet" "https://www.mouser.com/datasheet/2/240/media-3320461.pdf"
			(at 69.85 135.89 0)
			(effects
				(font
					(size 1.27 1.27)
					(thickness 0.15)
				)
				(justify left bottom)
				(hide yes)
			)
		)
		(property "Description" "ESD, TVS Diode, 14V, UNI, 400W, SOD-123FL"
			(at 85.09 120.65 0)
			(effects
				(font
					(size 1.27 1.27)
				)
				(hide yes)
			)
		)
		(property "MPN" "SZSMF4L12AT3G"
			(at 83.566 124.46 90)
			(effects
				(font
					(size 1.27 1.27)
					(thickness 0.15)
				)
				(justify right)
			)
		)
		(property "Author" "Antmicro"
			(at 67.31 135.89 0)
			(effects
				(font
					(size 1.27 1.27)
					(thickness 0.15)
				)
				(justify left bottom)
				(hide yes)
			)
		)
		(property "License" "Apache-2.0"
			(at 64.77 135.89 0)
			(effects
				(font
					(size 1.27 1.27)
					(thickness 0.15)
				)
				(justify left bottom)
				(hide yes)
			)
		)
		(property "Manufacturer" "Littelfuse"
			(at 62.23 135.89 0)
			(effects
				(font
					(size 1.27 1.27)
					(thickness 0.15)
				)
				(justify left bottom)
				(hide yes)
			)
		)
		(pin "1"
		)
		(pin "2"
		)
		(instances
			(project "oculink-to-pcie-adapter"
				(path ""
					(reference "D8")
					(unit 1)
				)
			)
		)
	)
	(symbol
		(lib_id "antmicroTVSDiodes:SZSMF4L14AT3G")
		(at 85.09 95.25 270)
		(unit 1)
		(exclude_from_sim no)
		(in_bom yes)
		(on_board yes)
		(dnp no)
		(property "Reference" "D7"
			(at 83.566 96.52 90)
			(effects
				(font
					(size 1.27 1.27)
					(thickness 0.15)
				)
				(justify right)
			)
		)
		(property "Value" "SZSMF4L14AT3G"
			(at 74.93 110.49 0)
			(effects
				(font
					(size 1.27 1.27)
					(thickness 0.15)
				)
				(justify left bottom)
				(hide yes)
			)
		)
		(property "Footprint" "antmicro-footprints:SOD-123FL"
			(at 72.39 110.49 0)
			(effects
				(font
					(size 1.27 1.27)
					(thickness 0.15)
				)
				(justify left bottom)
				(hide yes)
			)
		)
		(property "Datasheet" "https://www.mouser.com/datasheet/2/240/media-3320461.pdf"
			(at 69.85 110.49 0)
			(effects
				(font
					(size 1.27 1.27)
					(thickness 0.15)
				)
				(justify left bottom)
				(hide yes)
			)
		)
		(property "Description" "ESD, TVS Diode, 14V, UNI, 400W, SOD-123FL"
			(at 85.09 95.25 0)
			(effects
				(font
					(size 1.27 1.27)
				)
				(hide yes)
			)
		)
		(property "MPN" "SZSMF4L12AT3G"
			(at 83.566 99.06 90)
			(effects
				(font
					(size 1.27 1.27)
					(thickness 0.15)
				)
				(justify right)
			)
		)
		(property "Author" "Antmicro"
			(at 67.31 110.49 0)
			(effects
				(font
					(size 1.27 1.27)
					(thickness 0.15)
				)
				(justify left bottom)
				(hide yes)
			)
		)
		(property "License" "Apache-2.0"
			(at 64.77 110.49 0)
			(effects
				(font
					(size 1.27 1.27)
					(thickness 0.15)
				)
				(justify left bottom)
				(hide yes)
			)
		)
		(property "Manufacturer" "Littelfuse"
			(at 62.23 110.49 0)
			(effects
				(font
					(size 1.27 1.27)
					(thickness 0.15)
				)
				(justify left bottom)
				(hide yes)
			)
		)
		(pin "1"
		)
		(pin "2"
		)
		(instances
			(project "oculink-to-pcie-adapter"
				(path ""
					(reference "D7")
					(unit 1)
				)
			)
		)
	)
	(symbol
		(lib_id "antmicropower:GND")
		(at 223.52 102.87 0)
		(mirror y)
		(unit 1)
		(exclude_from_sim no)
		(in_bom yes)
		(on_board yes)
		(dnp no)
		(property "Reference" "#PWR013"
			(at 214.63 105.41 0)
			(effects
				(font
					(size 1.27 1.27)
					(thickness 0.15)
				)
				(justify left bottom)
				(hide yes)
			)
		)
		(property "Value" "GND"
			(at 223.52 106.68 0)
			(effects
				(font
					(size 1.27 1.27)
					(thickness 0.15)
				)
			)
		)
		(property "Footprint" ""
			(at 214.63 110.49 0)
			(effects
				(font
					(size 1.27 1.27)
					(thickness 0.15)
				)
				(justify left bottom)
				(hide yes)
			)
		)
		(property "Datasheet" ""
			(at 214.63 115.57 0)
			(effects
				(font
					(size 1.27 1.27)
					(thickness 0.15)
				)
				(justify left bottom)
				(hide yes)
			)
		)
		(property "Description" ""
			(at 223.52 102.87 0)
			(effects
				(font
					(size 1.27 1.27)
				)
				(hide yes)
			)
		)
		(property "Author" "Antmicro"
			(at 214.63 110.49 0)
			(effects
				(font
					(size 1.27 1.27)
					(thickness 0.15)
				)
				(justify left bottom)
				(hide yes)
			)
		)
		(property "License" "Apache-2.0"
			(at 214.63 113.03 0)
			(effects
				(font
					(size 1.27 1.27)
					(thickness 0.15)
				)
				(justify left bottom)
				(hide yes)
			)
		)
		(pin "1"
		)
		(instances
			(project "oculink-to-pcie-adapter"
				(path ""
					(reference "#PWR013")
					(unit 1)
				)
			)
		)
	)
	(symbol
		(lib_id "antmicroTransistorsFETsMOSFETsSingle:BSS138-7-F")
		(at 97.79 203.2 0)
		(unit 1)
		(exclude_from_sim no)
		(in_bom yes)
		(on_board yes)
		(dnp no)
		(fields_autoplaced yes)
		(property "Reference" "Q2"
			(at 109.22 199.39 0)
			(effects
				(font
					(size 1.27 1.27)
					(thickness 0.15)
				)
				(justify left)
			)
		)
		(property "Value" "BSS138-7-F"
			(at 120.65 208.28 0)
			(effects
				(font
					(size 1.27 1.27)
					(thickness 0.15)
				)
				(justify left bottom)
				(hide yes)
			)
		)
		(property "Footprint" "antmicro-footprints:SOT-23-3"
			(at 120.65 210.82 0)
			(effects
				(font
					(size 1.27 1.27)
					(thickness 0.15)
				)
				(justify left bottom)
				(hide yes)
			)
		)
		(property "Datasheet" "https://www.diodes.com/assets/Datasheets/ds30144.pdf"
			(at 120.65 213.36 0)
			(effects
				(font
					(size 1.27 1.27)
					(thickness 0.15)
				)
				(justify left bottom)
				(hide yes)
			)
		)
		(property "Description" "Power MOSFET, N Channel, 50 V, 200 mA, 1.4 ohm, SOT-23, Surface Mount"
			(at 157.734 225.044 0)
			(effects
				(font
					(size 1.27 1.27)
				)
				(hide yes)
			)
		)
		(property "MPN" "BSS138-7-F"
			(at 109.22 201.93 0)
			(effects
				(font
					(size 1.27 1.27)
					(thickness 0.15)
				)
				(justify left)
			)
		)
		(property "Manufacturer" "Diodes Incorporated"
			(at 120.65 218.44 0)
			(effects
				(font
					(size 1.27 1.27)
					(thickness 0.15)
				)
				(justify left bottom)
				(hide yes)
			)
		)
		(property "Author" "Antmicro"
			(at 120.65 220.98 0)
			(effects
				(font
					(size 1.27 1.27)
					(thickness 0.15)
				)
				(justify left bottom)
				(hide yes)
			)
		)
		(property "License" "Apache-2.0"
			(at 120.65 223.52 0)
			(effects
				(font
					(size 1.27 1.27)
					(thickness 0.15)
				)
				(justify left bottom)
				(hide yes)
			)
		)
		(pin "2"
		)
		(pin "3"
		)
		(pin "1"
		)
		(instances
			(project ""
				(path ""
					(reference "Q2")
					(unit 1)
				)
			)
		)
	)
	(symbol
		(lib_id "antmicroTestPoints:TP_Pad0.75mm_Drill0.2mm")
		(at 281.94 223.52 90)
		(unit 1)
		(exclude_from_sim no)
		(in_bom no)
		(on_board yes)
		(dnp no)
		(fields_autoplaced yes)
		(property "Reference" "TP1"
			(at 284.48 220.345 90)
			(effects
				(font
					(size 1.27 1.27)
					(thickness 0.15)
				)
				(justify right)
			)
		)
		(property "Value" "TP_Pad0.75mm_Drill0.2mm"
			(at 285.75 213.36 0)
			(effects
				(font
					(size 1.27 1.27)
					(thickness 0.15)
				)
				(justify left bottom)
				(hide yes)
			)
		)
		(property "Footprint" "antmicro-footprints:TP_Pad0.75mm_Drill0.2mm"
			(at 288.29 213.36 0)
			(effects
				(font
					(size 1.27 1.27)
					(thickness 0.15)
				)
				(justify left bottom)
				(hide yes)
			)
		)
		(property "Datasheet" ""
			(at 294.64 205.74 0)
			(effects
				(font
					(size 1.27 1.27)
					(thickness 0.15)
				)
				(justify left bottom)
				(hide yes)
			)
		)
		(property "Description" "SMT test point"
			(at 281.94 223.52 0)
			(effects
				(font
					(size 1.27 1.27)
				)
				(hide yes)
			)
		)
		(property "MPN" ""
			(at 293.37 212.725 0)
			(effects
				(font
					(size 1.27 1.27)
					(thickness 0.15)
				)
				(justify left bottom)
				(hide yes)
			)
		)
		(property "Manufacturer" ""
			(at 288.29 212.725 0)
			(effects
				(font
					(size 1.27 1.27)
					(thickness 0.15)
				)
				(justify left bottom)
				(hide yes)
			)
		)
		(property "Author" "Antmicro"
			(at 290.83 213.36 0)
			(effects
				(font
					(size 1.27 1.27)
					(thickness 0.15)
				)
				(justify left bottom)
				(hide yes)
			)
		)
		(property "License" "Apache-2.0"
			(at 293.37 213.36 0)
			(effects
				(font
					(size 1.27 1.27)
					(thickness 0.15)
				)
				(justify left bottom)
				(hide yes)
			)
		)
		(pin "1"
		)
		(instances
			(project ""
				(path ""
					(reference "TP1")
					(unit 1)
				)
			)
		)
	)
	(symbol
		(lib_id "antmicropower:GND")
		(at 132.08 260.35 0)
		(mirror y)
		(unit 1)
		(exclude_from_sim no)
		(in_bom yes)
		(on_board yes)
		(dnp no)
		(property "Reference" "#PWR031"
			(at 123.19 262.89 0)
			(effects
				(font
					(size 1.27 1.27)
					(thickness 0.15)
				)
				(justify left bottom)
				(hide yes)
			)
		)
		(property "Value" "GND"
			(at 132.08 264.16 0)
			(effects
				(font
					(size 1.27 1.27)
					(thickness 0.15)
				)
			)
		)
		(property "Footprint" ""
			(at 123.19 267.97 0)
			(effects
				(font
					(size 1.27 1.27)
					(thickness 0.15)
				)
				(justify left bottom)
				(hide yes)
			)
		)
		(property "Datasheet" ""
			(at 123.19 273.05 0)
			(effects
				(font
					(size 1.27 1.27)
					(thickness 0.15)
				)
				(justify left bottom)
				(hide yes)
			)
		)
		(property "Description" ""
			(at 132.08 260.35 0)
			(effects
				(font
					(size 1.27 1.27)
				)
				(hide yes)
			)
		)
		(property "Author" "Antmicro"
			(at 123.19 267.97 0)
			(effects
				(font
					(size 1.27 1.27)
					(thickness 0.15)
				)
				(justify left bottom)
				(hide yes)
			)
		)
		(property "License" "Apache-2.0"
			(at 123.19 270.51 0)
			(effects
				(font
					(size 1.27 1.27)
					(thickness 0.15)
				)
				(justify left bottom)
				(hide yes)
			)
		)
		(pin "1"
		)
		(instances
			(project "oculink-to-pcie-adapter"
				(path ""
					(reference "#PWR031")
					(unit 1)
				)
			)
		)
	)
	(symbol
		(lib_id "antmicropower:GND")
		(at 91.44 260.35 0)
		(mirror y)
		(unit 1)
		(exclude_from_sim no)
		(in_bom yes)
		(on_board yes)
		(dnp no)
		(property "Reference" "#PWR028"
			(at 82.55 262.89 0)
			(effects
				(font
					(size 1.27 1.27)
					(thickness 0.15)
				)
				(justify left bottom)
				(hide yes)
			)
		)
		(property "Value" "GND"
			(at 91.44 264.16 0)
			(effects
				(font
					(size 1.27 1.27)
					(thickness 0.15)
				)
			)
		)
		(property "Footprint" ""
			(at 82.55 267.97 0)
			(effects
				(font
					(size 1.27 1.27)
					(thickness 0.15)
				)
				(justify left bottom)
				(hide yes)
			)
		)
		(property "Datasheet" ""
			(at 82.55 273.05 0)
			(effects
				(font
					(size 1.27 1.27)
					(thickness 0.15)
				)
				(justify left bottom)
				(hide yes)
			)
		)
		(property "Description" ""
			(at 91.44 260.35 0)
			(effects
				(font
					(size 1.27 1.27)
				)
				(hide yes)
			)
		)
		(property "Author" "Antmicro"
			(at 82.55 267.97 0)
			(effects
				(font
					(size 1.27 1.27)
					(thickness 0.15)
				)
				(justify left bottom)
				(hide yes)
			)
		)
		(property "License" "Apache-2.0"
			(at 82.55 270.51 0)
			(effects
				(font
					(size 1.27 1.27)
					(thickness 0.15)
				)
				(justify left bottom)
				(hide yes)
			)
		)
		(pin "1"
		)
		(instances
			(project "oculink-to-pcie-adapter"
				(path ""
					(reference "#PWR028")
					(unit 1)
				)
			)
		)
	)
	(symbol
		(lib_id "antmicroCapacitorsmisc:C_22u_25V_0805")
		(at 233.68 90.17 90)
		(unit 1)
		(exclude_from_sim no)
		(in_bom yes)
		(on_board yes)
		(dnp no)
		(fields_autoplaced yes)
		(property "Reference" "C15"
			(at 236.22 85.0836 90)
			(effects
				(font
					(size 1.27 1.27)
					(thickness 0.15)
				)
				(justify right)
			)
		)
		(property "Value" "C_22u_25V_0805"
			(at 243.84 69.85 0)
			(effects
				(font
					(size 1.27 1.27)
					(thickness 0.15)
				)
				(justify left bottom)
				(hide yes)
			)
		)
		(property "Footprint" "antmicro-footprints:C_0805_2012Metric"
			(at 246.38 69.85 0)
			(effects
				(font
					(size 1.27 1.27)
					(thickness 0.15)
				)
				(justify left bottom)
				(hide yes)
			)
		)
		(property "Datasheet" "https://product.samsungsem.com/mlcc/CL21A226MAYNNN.do"
			(at 248.92 69.85 0)
			(effects
				(font
					(size 1.27 1.27)
					(thickness 0.15)
				)
				(justify left bottom)
				(hide yes)
			)
		)
		(property "Description" "SMT Multilayer Ceramic Capacitor, 22uF, +/-20%, 25V, X5R, 0805 [2012 Metric]"
			(at 233.68 90.17 0)
			(effects
				(font
					(size 1.27 1.27)
				)
				(hide yes)
			)
		)
		(property "MPN" "CL21A226MAYNNNE"
			(at 251.46 69.85 0)
			(effects
				(font
					(size 1.27 1.27)
					(thickness 0.15)
				)
				(justify left bottom)
				(hide yes)
			)
		)
		(property "Manufacturer" "Samsung Electro-Mechanics"
			(at 254 69.85 0)
			(effects
				(font
					(size 1.27 1.27)
					(thickness 0.15)
				)
				(justify left bottom)
				(hide yes)
			)
		)
		(property "License" "Apache-2.0"
			(at 256.54 69.85 0)
			(effects
				(font
					(size 1.27 1.27)
					(thickness 0.15)
				)
				(justify left bottom)
				(hide yes)
			)
		)
		(property "Author" "Antmicro"
			(at 259.08 69.85 0)
			(effects
				(font
					(size 1.27 1.27)
					(thickness 0.15)
				)
				(justify left bottom)
				(hide yes)
			)
		)
		(property "Val" "22u"
			(at 236.22 87.6236 90)
			(effects
				(font
					(size 1.27 1.27)
					(thickness 0.15)
				)
				(justify right)
			)
		)
		(property "Voltage" "25V"
			(at 236.22 90.1635 90)
			(effects
				(font
					(size 1.27 1.27)
				)
				(justify right)
			)
		)
		(property "Dielectric" "X5R"
			(at 264.16 69.85 0)
			(effects
				(font
					(size 1.27 1.27)
				)
				(justify left bottom)
				(hide yes)
			)
		)
		(property "Public" "False"
			(at 266.7 69.85 0)
			(effects
				(font
					(size 1.27 1.27)
				)
				(justify left bottom)
				(hide yes)
			)
		)
		(pin "2"
		)
		(pin "1"
		)
		(instances
			(project "oculink-to-pcie-adapter"
				(path ""
					(reference "C15")
					(unit 1)
				)
			)
		)
	)
	(symbol
		(lib_id "antmicroFuses:F_7A_1206")
		(at 69.85 92.71 0)
		(unit 1)
		(exclude_from_sim no)
		(in_bom yes)
		(on_board yes)
		(dnp no)
		(fields_autoplaced yes)
		(property "Reference" "F1"
			(at 72.39 87.63 0)
			(effects
				(font
					(size 1.27 1.27)
					(thickness 0.15)
				)
			)
		)
		(property "Value" "F_7A_1206"
			(at 91.44 100.33 0)
			(effects
				(font
					(size 1.27 1.27)
					(thickness 0.15)
				)
				(justify left bottom)
				(hide yes)
			)
		)
		(property "Footprint" "antmicro-footprints:F_1206_3216Metric"
			(at 91.44 102.87 0)
			(effects
				(font
					(size 1.27 1.27)
					(thickness 0.15)
				)
				(justify left bottom)
				(hide yes)
			)
		)
		(property "Datasheet" "https://us.schurter.com/pdf/english/typ_UST_1206.pdf"
			(at 91.44 105.41 0)
			(effects
				(font
					(size 1.27 1.27)
					(thickness 0.15)
				)
				(justify left bottom)
				(hide yes)
			)
		)
		(property "Description" "7 A 32 V AC 63 V DC Fuse Board Mount (Cartridge Style Excluded) Surface Mount 1206 (3216 Metric)"
			(at 69.85 92.71 0)
			(effects
				(font
					(size 1.27 1.27)
				)
				(hide yes)
			)
		)
		(property "Manufacturer" "Schurter"
			(at 91.44 107.95 0)
			(effects
				(font
					(size 1.27 1.27)
					(thickness 0.15)
				)
				(justify left bottom)
				(hide yes)
			)
		)
		(property "MPN" "3413.0326.11"
			(at 72.39 90.17 0)
			(effects
				(font
					(size 1.27 1.27)
					(thickness 0.15)
				)
			)
		)
		(property "Author" "Antmicro"
			(at 91.44 113.03 0)
			(effects
				(font
					(size 1.27 1.27)
					(thickness 0.15)
				)
				(justify left bottom)
				(hide yes)
			)
		)
		(property "License" "Apache-2.0"
			(at 91.44 115.57 0)
			(effects
				(font
					(size 1.27 1.27)
					(thickness 0.15)
				)
				(justify left bottom)
				(hide yes)
			)
		)
		(pin "1"
		)
		(pin "2"
		)
		(instances
			(project ""
				(path ""
					(reference "F1")
					(unit 1)
				)
			)
		)
	)
	(symbol
		(lib_id "antmicroTestPoints:TP_Pad0.75mm_Drill0.2mm")
		(at 335.28 226.06 0)
		(unit 1)
		(exclude_from_sim no)
		(in_bom no)
		(on_board yes)
		(dnp no)
		(fields_autoplaced yes)
		(property "Reference" "TP8"
			(at 340.36 226.06 0)
			(effects
				(font
					(size 1.27 1.27)
					(thickness 0.15)
				)
				(justify left)
			)
		)
		(property "Value" "TP_Pad0.75mm_Drill0.2mm"
			(at 345.44 229.87 0)
			(effects
				(font
					(size 1.27 1.27)
					(thickness 0.15)
				)
				(justify left bottom)
				(hide yes)
			)
		)
		(property "Footprint" "antmicro-footprints:TP_Pad0.75mm_Drill0.2mm"
			(at 345.44 232.41 0)
			(effects
				(font
					(size 1.27 1.27)
					(thickness 0.15)
				)
				(justify left bottom)
				(hide yes)
			)
		)
		(property "Datasheet" ""
			(at 353.06 238.76 0)
			(effects
				(font
					(size 1.27 1.27)
					(thickness 0.15)
				)
				(justify left bottom)
				(hide yes)
			)
		)
		(property "Description" "SMT test point"
			(at 335.28 226.06 0)
			(effects
				(font
					(size 1.27 1.27)
				)
				(hide yes)
			)
		)
		(property "MPN" ""
			(at 346.075 237.49 0)
			(effects
				(font
					(size 1.27 1.27)
					(thickness 0.15)
				)
				(justify left bottom)
				(hide yes)
			)
		)
		(property "Manufacturer" ""
			(at 346.075 232.41 0)
			(effects
				(font
					(size 1.27 1.27)
					(thickness 0.15)
				)
				(justify left bottom)
				(hide yes)
			)
		)
		(property "Author" "Antmicro"
			(at 345.44 234.95 0)
			(effects
				(font
					(size 1.27 1.27)
					(thickness 0.15)
				)
				(justify left bottom)
				(hide yes)
			)
		)
		(property "License" "Apache-2.0"
			(at 345.44 237.49 0)
			(effects
				(font
					(size 1.27 1.27)
					(thickness 0.15)
				)
				(justify left bottom)
				(hide yes)
			)
		)
		(pin "1"
		)
		(instances
			(project "oculink-to-pcie-adapter"
				(path ""
					(reference "TP8")
					(unit 1)
				)
			)
		)
	)
	(symbol
		(lib_id "antmicropower:GND")
		(at 105.41 213.36 0)
		(mirror y)
		(unit 1)
		(exclude_from_sim no)
		(in_bom yes)
		(on_board yes)
		(dnp no)
		(property "Reference" "#PWR030"
			(at 96.52 215.9 0)
			(effects
				(font
					(size 1.27 1.27)
					(thickness 0.15)
				)
				(justify left bottom)
				(hide yes)
			)
		)
		(property "Value" "GND"
			(at 105.41 217.17 0)
			(effects
				(font
					(size 1.27 1.27)
					(thickness 0.15)
				)
			)
		)
		(property "Footprint" ""
			(at 96.52 220.98 0)
			(effects
				(font
					(size 1.27 1.27)
					(thickness 0.15)
				)
				(justify left bottom)
				(hide yes)
			)
		)
		(property "Datasheet" ""
			(at 96.52 226.06 0)
			(effects
				(font
					(size 1.27 1.27)
					(thickness 0.15)
				)
				(justify left bottom)
				(hide yes)
			)
		)
		(property "Description" ""
			(at 105.41 213.36 0)
			(effects
				(font
					(size 1.27 1.27)
				)
				(hide yes)
			)
		)
		(property "Author" "Antmicro"
			(at 96.52 220.98 0)
			(effects
				(font
					(size 1.27 1.27)
					(thickness 0.15)
				)
				(justify left bottom)
				(hide yes)
			)
		)
		(property "License" "Apache-2.0"
			(at 96.52 223.52 0)
			(effects
				(font
					(size 1.27 1.27)
					(thickness 0.15)
				)
				(justify left bottom)
				(hide yes)
			)
		)
		(pin "1"
		)
		(instances
			(project "oculink-to-pcie-adapter"
				(path ""
					(reference "#PWR030")
					(unit 1)
				)
			)
		)
	)
	(symbol
		(lib_id "antmicroCapacitorsmisc:C_22u_25V_0805")
		(at 223.52 90.17 90)
		(unit 1)
		(exclude_from_sim no)
		(in_bom yes)
		(on_board yes)
		(dnp no)
		(fields_autoplaced yes)
		(property "Reference" "C2"
			(at 226.06 85.0836 90)
			(effects
				(font
					(size 1.27 1.27)
					(thickness 0.15)
				)
				(justify right)
			)
		)
		(property "Value" "C_22u_25V_0805"
			(at 233.68 69.85 0)
			(effects
				(font
					(size 1.27 1.27)
					(thickness 0.15)
				)
				(justify left bottom)
				(hide yes)
			)
		)
		(property "Footprint" "antmicro-footprints:C_0805_2012Metric"
			(at 236.22 69.85 0)
			(effects
				(font
					(size 1.27 1.27)
					(thickness 0.15)
				)
				(justify left bottom)
				(hide yes)
			)
		)
		(property "Datasheet" "https://product.samsungsem.com/mlcc/CL21A226MAYNNN.do"
			(at 238.76 69.85 0)
			(effects
				(font
					(size 1.27 1.27)
					(thickness 0.15)
				)
				(justify left bottom)
				(hide yes)
			)
		)
		(property "Description" "SMT Multilayer Ceramic Capacitor, 22uF, +/-20%, 25V, X5R, 0805 [2012 Metric]"
			(at 223.52 90.17 0)
			(effects
				(font
					(size 1.27 1.27)
				)
				(hide yes)
			)
		)
		(property "MPN" "CL21A226MAYNNNE"
			(at 241.3 69.85 0)
			(effects
				(font
					(size 1.27 1.27)
					(thickness 0.15)
				)
				(justify left bottom)
				(hide yes)
			)
		)
		(property "Manufacturer" "Samsung Electro-Mechanics"
			(at 243.84 69.85 0)
			(effects
				(font
					(size 1.27 1.27)
					(thickness 0.15)
				)
				(justify left bottom)
				(hide yes)
			)
		)
		(property "License" "Apache-2.0"
			(at 246.38 69.85 0)
			(effects
				(font
					(size 1.27 1.27)
					(thickness 0.15)
				)
				(justify left bottom)
				(hide yes)
			)
		)
		(property "Author" "Antmicro"
			(at 248.92 69.85 0)
			(effects
				(font
					(size 1.27 1.27)
					(thickness 0.15)
				)
				(justify left bottom)
				(hide yes)
			)
		)
		(property "Val" "22u"
			(at 226.06 87.6236 90)
			(effects
				(font
					(size 1.27 1.27)
					(thickness 0.15)
				)
				(justify right)
			)
		)
		(property "Voltage" "25V"
			(at 226.06 90.1635 90)
			(effects
				(font
					(size 1.27 1.27)
				)
				(justify right)
			)
		)
		(property "Dielectric" "X5R"
			(at 254 69.85 0)
			(effects
				(font
					(size 1.27 1.27)
				)
				(justify left bottom)
				(hide yes)
			)
		)
		(property "Public" "False"
			(at 256.54 69.85 0)
			(effects
				(font
					(size 1.27 1.27)
				)
				(justify left bottom)
				(hide yes)
			)
		)
		(pin "2"
		)
		(pin "1"
		)
		(instances
			(project "oculink-to-pcie-adapter"
				(path ""
					(reference "C2")
					(unit 1)
				)
			)
		)
	)
	(symbol
		(lib_id "antmicroResistors0603:R_0R_22.4A_0603")
		(at 373.38 77.47 0)
		(mirror y)
		(unit 1)
		(exclude_from_sim no)
		(in_bom no)
		(on_board yes)
		(dnp no)
		(property "Reference" "R53"
			(at 370.84 74.93 0)
			(effects
				(font
					(size 1.27 1.27)
					(thickness 0.15)
				)
			)
		)
		(property "Value" "R_0R_22.4A_0603"
			(at 369.57 79.248 90)
			(effects
				(font
					(size 1.27 1.27)
					(thickness 0.15)
				)
				(justify right)
				(hide yes)
			)
		)
		(property "Footprint" "antmicro-footprints:R_0603_1608Metric"
			(at 358.14 87.63 0)
			(effects
				(font
					(size 1.27 1.27)
					(thickness 0.15)
				)
				(justify left bottom)
				(hide yes)
			)
		)
		(property "Datasheet" "https://fscdn.rohm.com/en/products/databook/datasheet/passive/resistor/chip_resistor/pmr-jpw-e.pdf"
			(at 358.14 90.17 0)
			(effects
				(font
					(size 1.27 1.27)
					(thickness 0.15)
				)
				(justify left bottom)
				(hide yes)
			)
		)
		(property "Description" "SMD Chip Resistor"
			(at 373.38 77.47 0)
			(effects
				(font
					(size 1.27 1.27)
				)
				(hide yes)
			)
		)
		(property "MPN" "PMR03EZPJ000"
			(at 358.14 92.71 0)
			(effects
				(font
					(size 1.27 1.27)
					(thickness 0.15)
				)
				(justify left bottom)
				(hide yes)
			)
		)
		(property "Manufacturer" "ROHM Semiconductor"
			(at 358.14 95.25 0)
			(effects
				(font
					(size 1.27 1.27)
					(thickness 0.15)
				)
				(justify left bottom)
				(hide yes)
			)
		)
		(property "Val" "0R"
			(at 367.03 78.74 0)
			(effects
				(font
					(size 1.27 1.27)
					(thickness 0.15)
				)
			)
		)
		(property "Max. Curr." "22.4A"
			(at 375.92 78.74 0)
			(effects
				(font
					(size 1.27 1.27)
					(thickness 0.15)
				)
			)
		)
		(property "Author" "Antmicro"
			(at 358.14 100.33 0)
			(effects
				(font
					(size 1.27 1.27)
					(thickness 0.15)
				)
				(justify left bottom)
				(hide yes)
			)
		)
		(property "License" "Apache-2.0"
			(at 358.14 102.87 0)
			(effects
				(font
					(size 1.27 1.27)
					(thickness 0.15)
				)
				(justify left bottom)
				(hide yes)
			)
		)
		(property "Tolerance" "template_tolerance"
			(at 353.06 87.63 0)
			(effects
				(font
					(size 1.27 1.27)
				)
				(justify left bottom)
				(hide yes)
			)
		)
		(pin "1"
		)
		(pin "2"
		)
		(instances
			(project "oculink-to-pcie-adapter"
				(path ""
					(reference "R53")
					(unit 1)
				)
			)
		)
	)
	(symbol
		(lib_id "antmicroTestPoints:TP_Pad0.75mm_Drill0.2mm")
		(at 363.22 82.55 0)
		(unit 1)
		(exclude_from_sim no)
		(in_bom no)
		(on_board yes)
		(dnp no)
		(fields_autoplaced yes)
		(property "Reference" "TP7"
			(at 368.3 82.55 0)
			(effects
				(font
					(size 1.27 1.27)
					(thickness 0.15)
				)
				(justify left)
			)
		)
		(property "Value" "TP_Pad0.75mm_Drill0.2mm"
			(at 373.38 86.36 0)
			(effects
				(font
					(size 1.27 1.27)
					(thickness 0.15)
				)
				(justify left bottom)
				(hide yes)
			)
		)
		(property "Footprint" "antmicro-footprints:TP_Pad0.75mm_Drill0.2mm"
			(at 373.38 88.9 0)
			(effects
				(font
					(size 1.27 1.27)
					(thickness 0.15)
				)
				(justify left bottom)
				(hide yes)
			)
		)
		(property "Datasheet" ""
			(at 381 95.25 0)
			(effects
				(font
					(size 1.27 1.27)
					(thickness 0.15)
				)
				(justify left bottom)
				(hide yes)
			)
		)
		(property "Description" "SMT test point"
			(at 363.22 82.55 0)
			(effects
				(font
					(size 1.27 1.27)
				)
				(hide yes)
			)
		)
		(property "MPN" ""
			(at 374.015 93.98 0)
			(effects
				(font
					(size 1.27 1.27)
					(thickness 0.15)
				)
				(justify left bottom)
				(hide yes)
			)
		)
		(property "Manufacturer" ""
			(at 374.015 88.9 0)
			(effects
				(font
					(size 1.27 1.27)
					(thickness 0.15)
				)
				(justify left bottom)
				(hide yes)
			)
		)
		(property "Author" "Antmicro"
			(at 373.38 91.44 0)
			(effects
				(font
					(size 1.27 1.27)
					(thickness 0.15)
				)
				(justify left bottom)
				(hide yes)
			)
		)
		(property "License" "Apache-2.0"
			(at 373.38 93.98 0)
			(effects
				(font
					(size 1.27 1.27)
					(thickness 0.15)
				)
				(justify left bottom)
				(hide yes)
			)
		)
		(pin "1"
		)
		(instances
			(project "oculink-to-pcie-adapter"
				(path ""
					(reference "TP7")
					(unit 1)
				)
			)
		)
	)
	(symbol
		(lib_id "antmicropower:GND")
		(at 350.52 102.87 0)
		(unit 1)
		(exclude_from_sim no)
		(in_bom yes)
		(on_board yes)
		(dnp no)
		(fields_autoplaced yes)
		(property "Reference" "#PWR020"
			(at 359.41 105.41 0)
			(effects
				(font
					(size 1.27 1.27)
					(thickness 0.15)
				)
				(justify left bottom)
				(hide yes)
			)
		)
		(property "Value" "GND"
			(at 350.52 106.68 0)
			(effects
				(font
					(size 1.27 1.27)
					(thickness 0.15)
				)
			)
		)
		(property "Footprint" ""
			(at 359.41 110.49 0)
			(effects
				(font
					(size 1.27 1.27)
					(thickness 0.15)
				)
				(justify left bottom)
				(hide yes)
			)
		)
		(property "Datasheet" ""
			(at 359.41 115.57 0)
			(effects
				(font
					(size 1.27 1.27)
					(thickness 0.15)
				)
				(justify left bottom)
				(hide yes)
			)
		)
		(property "Description" ""
			(at 350.52 102.87 0)
			(effects
				(font
					(size 1.27 1.27)
				)
				(hide yes)
			)
		)
		(property "Author" "Antmicro"
			(at 359.41 110.49 0)
			(effects
				(font
					(size 1.27 1.27)
					(thickness 0.15)
				)
				(justify left bottom)
				(hide yes)
			)
		)
		(property "License" "Apache-2.0"
			(at 359.41 113.03 0)
			(effects
				(font
					(size 1.27 1.27)
					(thickness 0.15)
				)
				(justify left bottom)
				(hide yes)
			)
		)
		(pin "1"
		)
		(instances
			(project "oculink-to-pcie-adapter"
				(path ""
					(reference "#PWR020")
					(unit 1)
				)
			)
		)
	)
	(symbol
		(lib_id "antmicroResistors0402:R_0R_0402")
		(at 114.3 254 0)
		(unit 1)
		(exclude_from_sim no)
		(in_bom yes)
		(on_board yes)
		(dnp no)
		(property "Reference" "R13"
			(at 113.03 252.73 0)
			(effects
				(font
					(size 1.27 1.27)
					(thickness 0.15)
				)
			)
		)
		(property "Value" "R_0R_0402"
			(at 134.62 266.7 0)
			(effects
				(font
					(size 1.27 1.27)
					(thickness 0.15)
				)
				(justify left bottom)
				(hide yes)
			)
		)
		(property "Footprint" "antmicro-footprints:R_0402_1005Metric"
			(at 134.62 269.24 0)
			(effects
				(font
					(size 1.27 1.27)
					(thickness 0.15)
				)
				(justify left bottom)
				(hide yes)
			)
		)
		(property "Datasheet" "https://industrial.panasonic.com/cdbs/www-data/pdf/RDA0000/AOA0000C301.pdf"
			(at 134.62 271.78 0)
			(effects
				(font
					(size 1.27 1.27)
					(thickness 0.15)
				)
				(justify left bottom)
				(hide yes)
			)
		)
		(property "Description" "SMD Chip Resistor, Jumper, 0 ohm, 100 mW, 0402 [1005 Metric], Thick Film, General Purpose"
			(at 114.3 254 0)
			(effects
				(font
					(size 1.27 1.27)
				)
				(hide yes)
			)
		)
		(property "MPN" "ERJ2GE0R00X"
			(at 134.62 274.32 0)
			(effects
				(font
					(size 1.27 1.27)
					(thickness 0.15)
				)
				(justify left bottom)
				(hide yes)
			)
		)
		(property "Manufacturer" "Panasonic"
			(at 134.62 276.86 0)
			(effects
				(font
					(size 1.27 1.27)
					(thickness 0.15)
				)
				(justify left bottom)
				(hide yes)
			)
		)
		(property "License" "Apache-2.0"
			(at 134.62 279.4 0)
			(effects
				(font
					(size 1.27 1.27)
					(thickness 0.15)
				)
				(justify left bottom)
				(hide yes)
			)
		)
		(property "Author" "Antmicro"
			(at 134.62 281.94 0)
			(effects
				(font
					(size 1.27 1.27)
					(thickness 0.15)
				)
				(justify left bottom)
				(hide yes)
			)
		)
		(property "Val" "0R"
			(at 120.65 252.73 0)
			(effects
				(font
					(size 1.27 1.27)
					(thickness 0.15)
				)
			)
		)
		(property "Tolerance" "~"
			(at 134.62 264.16 0)
			(effects
				(font
					(size 1.27 1.27)
				)
				(justify left bottom)
				(hide yes)
			)
		)
		(property "Current" "1A"
			(at 134.62 284.48 0)
			(effects
				(font
					(size 1.27 1.27)
					(thickness 0.15)
				)
				(justify left bottom)
				(hide yes)
			)
		)
		(pin "2"
		)
		(pin "1"
		)
		(instances
			(project ""
				(path ""
					(reference "R13")
					(unit 1)
				)
			)
		)
	)
	(symbol
		(lib_id "antmicropower:GND")
		(at 264.16 102.87 0)
		(mirror y)
		(unit 1)
		(exclude_from_sim no)
		(in_bom yes)
		(on_board yes)
		(dnp no)
		(fields_autoplaced yes)
		(property "Reference" "#PWR016"
			(at 255.27 105.41 0)
			(effects
				(font
					(size 1.27 1.27)
					(thickness 0.15)
				)
				(justify left bottom)
				(hide yes)
			)
		)
		(property "Value" "GND"
			(at 264.16 106.68 0)
			(effects
				(font
					(size 1.27 1.27)
					(thickness 0.15)
				)
			)
		)
		(property "Footprint" ""
			(at 255.27 110.49 0)
			(effects
				(font
					(size 1.27 1.27)
					(thickness 0.15)
				)
				(justify left bottom)
				(hide yes)
			)
		)
		(property "Datasheet" ""
			(at 255.27 115.57 0)
			(effects
				(font
					(size 1.27 1.27)
					(thickness 0.15)
				)
				(justify left bottom)
				(hide yes)
			)
		)
		(property "Description" ""
			(at 264.16 102.87 0)
			(effects
				(font
					(size 1.27 1.27)
				)
				(hide yes)
			)
		)
		(property "Author" "Antmicro"
			(at 255.27 110.49 0)
			(effects
				(font
					(size 1.27 1.27)
					(thickness 0.15)
				)
				(justify left bottom)
				(hide yes)
			)
		)
		(property "License" "Apache-2.0"
			(at 255.27 113.03 0)
			(effects
				(font
					(size 1.27 1.27)
					(thickness 0.15)
				)
				(justify left bottom)
				(hide yes)
			)
		)
		(pin "1"
		)
		(instances
			(project "oculink-to-pcie-adapter"
				(path ""
					(reference "#PWR016")
					(unit 1)
				)
			)
		)
	)
	(symbol
		(lib_id "antmicroCapacitors0402:C_1u_25V_0402")
		(at 350.52 93.98 90)
		(unit 1)
		(exclude_from_sim no)
		(in_bom yes)
		(on_board yes)
		(dnp no)
		(property "Reference" "C5"
			(at 352.806 90.17 90)
			(effects
				(font
					(size 1.27 1.27)
					(thickness 0.15)
				)
				(justify right)
			)
		)
		(property "Value" "C_1u_25V_0402"
			(at 360.68 73.66 0)
			(effects
				(font
					(size 1.27 1.27)
					(thickness 0.15)
				)
				(justify left bottom)
				(hide yes)
			)
		)
		(property "Footprint" "antmicro-footprints:C_0402_1005Metric"
			(at 363.22 73.66 0)
			(effects
				(font
					(size 1.27 1.27)
					(thickness 0.15)
				)
				(justify left bottom)
				(hide yes)
			)
		)
		(property "Datasheet" "https://www.murata.com/products/productdetail?partno=GRM155R61E105KE11%23"
			(at 365.76 73.66 0)
			(effects
				(font
					(size 1.27 1.27)
					(thickness 0.15)
				)
				(justify left bottom)
				(hide yes)
			)
		)
		(property "Description" "SMD Multilayer Ceramic Capacitor, 1 µF, 25 V, 0402 [1005 Metric], ± 10%, X5R, GRM Series"
			(at 350.52 93.98 0)
			(effects
				(font
					(size 1.27 1.27)
				)
				(hide yes)
			)
		)
		(property "MPN" "GRM155R61E105KE11J"
			(at 368.3 73.66 0)
			(effects
				(font
					(size 1.27 1.27)
					(thickness 0.15)
				)
				(justify left bottom)
				(hide yes)
			)
		)
		(property "Manufacturer" "Murata"
			(at 370.84 73.66 0)
			(effects
				(font
					(size 1.27 1.27)
					(thickness 0.15)
				)
				(justify left bottom)
				(hide yes)
			)
		)
		(property "License" "Apache-2.0"
			(at 373.38 73.66 0)
			(effects
				(font
					(size 1.27 1.27)
					(thickness 0.15)
				)
				(justify left bottom)
				(hide yes)
			)
		)
		(property "Author" "Antmicro"
			(at 375.92 73.66 0)
			(effects
				(font
					(size 1.27 1.27)
					(thickness 0.15)
				)
				(justify left bottom)
				(hide yes)
			)
		)
		(property "Val" "1u"
			(at 352.806 92.71 90)
			(effects
				(font
					(size 1.27 1.27)
					(thickness 0.15)
				)
				(justify right)
			)
		)
		(property "Voltage" "25V"
			(at 378.46 73.66 0)
			(effects
				(font
					(size 1.27 1.27)
				)
				(justify left bottom)
				(hide yes)
			)
		)
		(property "Dielectric" "X5R"
			(at 381 73.66 0)
			(effects
				(font
					(size 1.27 1.27)
				)
				(justify left bottom)
				(hide yes)
			)
		)
		(pin "2"
		)
		(pin "1"
		)
		(instances
			(project "oculink-to-pcie-adapter"
				(path ""
					(reference "C5")
					(unit 1)
				)
			)
		)
	)
	(symbol
		(lib_id "antmicropower:GND")
		(at 147.32 88.9 0)
		(unit 1)
		(exclude_from_sim no)
		(in_bom yes)
		(on_board yes)
		(dnp no)
		(property "Reference" "#PWR079"
			(at 147.32 88.9 0)
			(effects
				(font
					(size 1.27 1.27)
				)
				(justify left)
				(hide yes)
			)
		)
		(property "Value" "GND"
			(at 147.32 92.71 0)
			(effects
				(font
					(size 1.27 1.27)
				)
			)
		)
		(property "Footprint" ""
			(at 147.32 88.9 0)
			(effects
				(font
					(size 1.27 1.27)
					(thickness 0.15)
				)
				(justify left bottom)
				(hide yes)
			)
		)
		(property "Datasheet" ""
			(at 147.32 88.9 0)
			(effects
				(font
					(size 1.27 1.27)
					(thickness 0.15)
				)
				(justify left bottom)
				(hide yes)
			)
		)
		(property "Description" ""
			(at 147.32 88.9 0)
			(effects
				(font
					(size 1.27 1.27)
				)
				(hide yes)
			)
		)
		(property "Author" "Antmicro"
			(at 156.21 96.52 0)
			(effects
				(font
					(size 1.27 1.27)
					(thickness 0.15)
				)
				(justify left bottom)
				(hide yes)
			)
		)
		(property "License" "Apache-2.0"
			(at 156.21 99.06 0)
			(effects
				(font
					(size 1.27 1.27)
					(thickness 0.15)
				)
				(justify left bottom)
				(hide yes)
			)
		)
		(pin "1"
		)
		(instances
			(project "oculink-to-pcie-adapter"
				(path ""
					(reference "#PWR079")
					(unit 1)
				)
			)
		)
	)
	(symbol
		(lib_id "antmicropower:PWR_FLAG")
		(at 209.55 97.79 0)
		(unit 1)
		(exclude_from_sim no)
		(in_bom yes)
		(on_board yes)
		(dnp no)
		(property "Reference" "#FLG02"
			(at 209.55 95.885 0)
			(effects
				(font
					(size 1.27 1.27)
				)
				(hide yes)
			)
		)
		(property "Value" "PWR_FLAG"
			(at 209.55 93.98 0)
			(effects
				(font
					(size 1.27 1.27)
				)
			)
		)
		(property "Footprint" ""
			(at 209.55 97.79 0)
			(effects
				(font
					(size 1.27 1.27)
				)
				(hide yes)
			)
		)
		(property "Datasheet" ""
			(at 209.55 97.79 0)
			(effects
				(font
					(size 1.27 1.27)
				)
				(hide yes)
			)
		)
		(property "Description" ""
			(at 209.55 97.79 0)
			(effects
				(font
					(size 1.27 1.27)
				)
				(hide yes)
			)
		)
		(pin "1"
		)
		(instances
			(project "oculink-to-pcie-adapter"
				(path ""
					(reference "#FLG02")
					(unit 1)
				)
			)
		)
	)
	(symbol
		(lib_id "antmicroResistors0402:R_1k_0402")
		(at 317.5 215.9 90)
		(unit 1)
		(exclude_from_sim no)
		(in_bom yes)
		(on_board yes)
		(dnp no)
		(property "Reference" "R14"
			(at 318.77 212.09 90)
			(effects
				(font
					(size 1.27 1.27)
					(thickness 0.15)
				)
				(justify right)
			)
		)
		(property "Value" "R_1k_0402"
			(at 330.2 195.58 0)
			(effects
				(font
					(size 1.27 1.27)
					(thickness 0.15)
				)
				(justify left bottom)
				(hide yes)
			)
		)
		(property "Footprint" "antmicro-footprints:R_0402_1005Metric"
			(at 332.74 195.58 0)
			(effects
				(font
					(size 1.27 1.27)
					(thickness 0.15)
				)
				(justify left bottom)
				(hide yes)
			)
		)
		(property "Datasheet" "https://www.bourns.com/docs/product-datasheets/cr.pdf"
			(at 335.28 195.58 0)
			(effects
				(font
					(size 1.27 1.27)
					(thickness 0.15)
				)
				(justify left bottom)
				(hide yes)
			)
		)
		(property "Description" "SMD Chip Resistor, 1 kohm, ± 1%, 63 mW, 0402 [1005 Metric], Thick Film, General Purpose"
			(at 317.5 215.9 0)
			(effects
				(font
					(size 1.27 1.27)
				)
				(hide yes)
			)
		)
		(property "MPN" "CR0402-FX-1001GLF"
			(at 337.82 195.58 0)
			(effects
				(font
					(size 1.27 1.27)
					(thickness 0.15)
				)
				(justify left bottom)
				(hide yes)
			)
		)
		(property "Manufacturer" "Bourns"
			(at 340.36 195.58 0)
			(effects
				(font
					(size 1.27 1.27)
					(thickness 0.15)
				)
				(justify left bottom)
				(hide yes)
			)
		)
		(property "License" "Apache-2.0"
			(at 342.9 195.58 0)
			(effects
				(font
					(size 1.27 1.27)
					(thickness 0.15)
				)
				(justify left bottom)
				(hide yes)
			)
		)
		(property "Author" "Antmicro"
			(at 345.44 195.58 0)
			(effects
				(font
					(size 1.27 1.27)
					(thickness 0.15)
				)
				(justify left bottom)
				(hide yes)
			)
		)
		(property "Val" "1k"
			(at 318.77 214.63 90)
			(effects
				(font
					(size 1.27 1.27)
					(thickness 0.15)
				)
				(justify right)
			)
		)
		(property "Tolerance" "1%"
			(at 327.66 195.58 0)
			(effects
				(font
					(size 1.27 1.27)
				)
				(justify left bottom)
				(hide yes)
			)
		)
		(pin "2"
		)
		(pin "1"
		)
		(instances
			(project ""
				(path ""
					(reference "R14")
					(unit 1)
				)
			)
		)
	)
	(symbol
		(lib_id "antmicroLEDIndicationDiscrete:LED_G_0603_LTST-C190GKT")
		(at 317.5 208.28 90)
		(unit 1)
		(exclude_from_sim no)
		(in_bom yes)
		(on_board yes)
		(dnp no)
		(fields_autoplaced yes)
		(property "Reference" "D3"
			(at 320.04 204.47 90)
			(effects
				(font
					(size 1.27 1.27)
					(thickness 0.15)
				)
				(justify right)
			)
		)
		(property "Value" "LED_G_0603_LTST-C190GKT"
			(at 325.12 185.42 0)
			(effects
				(font
					(size 1.27 1.27)
					(thickness 0.15)
				)
				(justify left bottom)
				(hide yes)
			)
		)
		(property "Footprint" "antmicro-footprints:LED_0603_1608Metric_G"
			(at 327.66 185.42 0)
			(effects
				(font
					(size 1.27 1.27)
					(thickness 0.15)
				)
				(justify left bottom)
				(hide yes)
			)
		)
		(property "Datasheet" "https://media.digikey.com/pdf/Data%20Sheets/Lite-On%20PDFs/LTST-C190GKT.pdf"
			(at 330.2 185.42 0)
			(effects
				(font
					(size 1.27 1.27)
					(thickness 0.15)
				)
				(justify left bottom)
				(hide yes)
			)
		)
		(property "Description" "LED, Green, SMD, 0603, 20 mA, 2.1 V, 569 nm"
			(at 317.5 208.28 0)
			(effects
				(font
					(size 1.27 1.27)
				)
				(hide yes)
			)
		)
		(property "MPN" "LTST-C190GKT"
			(at 332.74 185.42 0)
			(effects
				(font
					(size 1.27 1.27)
					(thickness 0.15)
				)
				(justify left bottom)
				(hide yes)
			)
		)
		(property "Manufacturer" "Lite-On"
			(at 335.28 185.42 0)
			(effects
				(font
					(size 1.27 1.27)
					(thickness 0.15)
				)
				(justify left bottom)
				(hide yes)
			)
		)
		(property "Color" "Green"
			(at 320.04 207.0099 90)
			(effects
				(font
					(size 1.27 1.27)
				)
				(justify right)
			)
		)
		(property "Author" "Antmicro"
			(at 337.82 185.42 0)
			(effects
				(font
					(size 1.27 1.27)
					(thickness 0.15)
				)
				(justify left bottom)
				(hide yes)
			)
		)
		(property "License" "Apache-2.0"
			(at 340.36 185.42 0)
			(effects
				(font
					(size 1.27 1.27)
					(thickness 0.15)
				)
				(justify left bottom)
				(hide yes)
			)
		)
		(pin "2"
		)
		(pin "1"
		)
		(instances
			(project "oculink-to-pcie-adapter"
				(path ""
					(reference "D3")
					(unit 1)
				)
			)
		)
	)
	(symbol
		(lib_id "antmicropower:GND")
		(at 242.57 102.87 0)
		(mirror y)
		(unit 1)
		(exclude_from_sim no)
		(in_bom yes)
		(on_board yes)
		(dnp no)
		(fields_autoplaced yes)
		(property "Reference" "#PWR014"
			(at 233.68 105.41 0)
			(effects
				(font
					(size 1.27 1.27)
					(thickness 0.15)
				)
				(justify left bottom)
				(hide yes)
			)
		)
		(property "Value" "GND"
			(at 242.57 106.68 0)
			(effects
				(font
					(size 1.27 1.27)
					(thickness 0.15)
				)
			)
		)
		(property "Footprint" ""
			(at 233.68 110.49 0)
			(effects
				(font
					(size 1.27 1.27)
					(thickness 0.15)
				)
				(justify left bottom)
				(hide yes)
			)
		)
		(property "Datasheet" ""
			(at 233.68 115.57 0)
			(effects
				(font
					(size 1.27 1.27)
					(thickness 0.15)
				)
				(justify left bottom)
				(hide yes)
			)
		)
		(property "Description" ""
			(at 242.57 102.87 0)
			(effects
				(font
					(size 1.27 1.27)
				)
				(hide yes)
			)
		)
		(property "Author" "Antmicro"
			(at 233.68 110.49 0)
			(effects
				(font
					(size 1.27 1.27)
					(thickness 0.15)
				)
				(justify left bottom)
				(hide yes)
			)
		)
		(property "License" "Apache-2.0"
			(at 233.68 113.03 0)
			(effects
				(font
					(size 1.27 1.27)
					(thickness 0.15)
				)
				(justify left bottom)
				(hide yes)
			)
		)
		(pin "1"
		)
		(instances
			(project "oculink-to-pcie-adapter"
				(path ""
					(reference "#PWR014")
					(unit 1)
				)
			)
		)
	)
	(symbol
		(lib_id "antmicroResistors0402:R_10k_0402")
		(at 271.78 96.52 270)
		(unit 1)
		(exclude_from_sim no)
		(in_bom yes)
		(on_board yes)
		(dnp no)
		(property "Reference" "R16"
			(at 273.304 97.79 90)
			(effects
				(font
					(size 1.27 1.27)
					(thickness 0.15)
				)
				(justify left)
			)
		)
		(property "Value" "R_10k_0402"
			(at 259.08 116.84 0)
			(effects
				(font
					(size 1.27 1.27)
					(thickness 0.15)
				)
				(justify left bottom)
				(hide yes)
			)
		)
		(property "Footprint" "antmicro-footprints:R_0402_1005Metric"
			(at 256.54 116.84 0)
			(effects
				(font
					(size 1.27 1.27)
					(thickness 0.15)
				)
				(justify left bottom)
				(hide yes)
			)
		)
		(property "Datasheet" "https://www.bourns.com/docs/product-datasheets/cr.pdf"
			(at 254 116.84 0)
			(effects
				(font
					(size 1.27 1.27)
					(thickness 0.15)
				)
				(justify left bottom)
				(hide yes)
			)
		)
		(property "Description" "SMD Chip Resistor, 10 kohm, ± 1%, 62.5 mW, 0402 [1005 Metric], Thick Film, General Purpose"
			(at 271.78 96.52 0)
			(effects
				(font
					(size 1.27 1.27)
				)
				(hide yes)
			)
		)
		(property "MPN" "CR0402-FX-1002GLF"
			(at 251.46 116.84 0)
			(effects
				(font
					(size 1.27 1.27)
					(thickness 0.15)
				)
				(justify left bottom)
				(hide yes)
			)
		)
		(property "Manufacturer" "Bourns"
			(at 248.92 116.84 0)
			(effects
				(font
					(size 1.27 1.27)
					(thickness 0.15)
				)
				(justify left bottom)
				(hide yes)
			)
		)
		(property "License" "Apache-2.0"
			(at 246.38 116.84 0)
			(effects
				(font
					(size 1.27 1.27)
					(thickness 0.15)
				)
				(justify left bottom)
				(hide yes)
			)
		)
		(property "Author" "Antmicro"
			(at 243.84 116.84 0)
			(effects
				(font
					(size 1.27 1.27)
					(thickness 0.15)
				)
				(justify left bottom)
				(hide yes)
			)
		)
		(property "Val" "10k"
			(at 273.304 100.33 90)
			(effects
				(font
					(size 1.27 1.27)
					(thickness 0.15)
				)
				(justify left)
			)
		)
		(property "Tolerance" "1%"
			(at 261.62 116.84 0)
			(effects
				(font
					(size 1.27 1.27)
				)
				(justify left bottom)
				(hide yes)
			)
		)
		(pin "1"
		)
		(pin "2"
		)
		(instances
			(project "oculink-to-pcie-adapter"
				(path ""
					(reference "R16")
					(unit 1)
				)
			)
		)
	)
	(symbol
		(lib_id "antmicroCapacitorspol:C_Pol_150u_30V_Vishay-T59-EE")
		(at 147.32 82.55 270)
		(unit 1)
		(exclude_from_sim no)
		(in_bom yes)
		(on_board yes)
		(dnp no)
		(fields_autoplaced yes)
		(property "Reference" "C30"
			(at 149.86 83.2866 90)
			(effects
				(font
					(size 1.27 1.27)
					(thickness 0.15)
				)
				(justify left)
			)
		)
		(property "Value" "C_Pol_150u_30V_Vishay-T59-EE"
			(at 137.16 97.79 0)
			(effects
				(font
					(size 1.27 1.27)
					(thickness 0.15)
				)
				(justify left bottom)
				(hide yes)
			)
		)
		(property "Footprint" "antmicro-footprints:C_Pol_Vishay-T59-EE"
			(at 134.62 97.79 0)
			(effects
				(font
					(size 1.27 1.27)
					(thickness 0.15)
				)
				(justify left bottom)
				(hide yes)
			)
		)
		(property "Datasheet" "https://www.vishay.com/docs/40191/t59.pdf"
			(at 132.08 97.79 0)
			(effects
				(font
					(size 1.27 1.27)
					(thickness 0.15)
				)
				(justify left bottom)
				(hide yes)
			)
		)
		(property "Description" "Tantalum Capacitors - Polymer 150uF 30volts 20% 75mohms maxESR"
			(at 147.32 82.55 0)
			(effects
				(font
					(size 1.27 1.27)
				)
				(hide yes)
			)
		)
		(property "MPN" "T59EE157M030C0075"
			(at 134.62 96.52 0)
			(effects
				(font
					(size 1.27 1.27)
				)
				(justify left bottom)
				(hide yes)
			)
		)
		(property "Manufacturer" "Vishay"
			(at 129.54 97.79 0)
			(effects
				(font
					(size 1.27 1.27)
					(thickness 0.15)
				)
				(justify left bottom)
				(hide yes)
			)
		)
		(property "Voltage" "30V"
			(at 127 97.79 0)
			(effects
				(font
					(size 1.27 1.27)
					(thickness 0.15)
				)
				(justify left bottom)
				(hide yes)
			)
		)
		(property "Val" "150u"
			(at 149.86 85.8266 90)
			(effects
				(font
					(size 1.27 1.27)
					(thickness 0.15)
				)
				(justify left)
			)
		)
		(property "Author" "Antmicro"
			(at 124.46 97.79 0)
			(effects
				(font
					(size 1.27 1.27)
					(thickness 0.15)
				)
				(justify left bottom)
				(hide yes)
			)
		)
		(property "License" "Apache-2.0"
			(at 121.92 97.79 0)
			(effects
				(font
					(size 1.27 1.27)
					(thickness 0.15)
				)
				(justify left bottom)
				(hide yes)
			)
		)
		(property "Dielectric" "template_dielectric"
			(at 121.92 96.52 0)
			(effects
				(font
					(size 1.27 1.27)
				)
				(justify left bottom)
				(hide yes)
			)
		)
		(pin "2"
		)
		(pin "1"
		)
		(instances
			(project "oculink-to-pcie-adapter"
				(path ""
					(reference "C30")
					(unit 1)
				)
			)
		)
	)
	(symbol
		(lib_id "antmicroCapacitors0402:C_1u_25V_0402")
		(at 264.16 97.79 90)
		(unit 1)
		(exclude_from_sim no)
		(in_bom yes)
		(on_board yes)
		(dnp no)
		(property "Reference" "C7"
			(at 266.446 93.98 90)
			(effects
				(font
					(size 1.27 1.27)
					(thickness 0.15)
				)
				(justify right)
			)
		)
		(property "Value" "C_1u_25V_0402"
			(at 274.32 77.47 0)
			(effects
				(font
					(size 1.27 1.27)
					(thickness 0.15)
				)
				(justify left bottom)
				(hide yes)
			)
		)
		(property "Footprint" "antmicro-footprints:C_0402_1005Metric"
			(at 276.86 77.47 0)
			(effects
				(font
					(size 1.27 1.27)
					(thickness 0.15)
				)
				(justify left bottom)
				(hide yes)
			)
		)
		(property "Datasheet" "https://www.murata.com/products/productdetail?partno=GRM155R61E105KE11%23"
			(at 279.4 77.47 0)
			(effects
				(font
					(size 1.27 1.27)
					(thickness 0.15)
				)
				(justify left bottom)
				(hide yes)
			)
		)
		(property "Description" "SMD Multilayer Ceramic Capacitor, 1 µF, 25 V, 0402 [1005 Metric], ± 10%, X5R, GRM Series"
			(at 264.16 97.79 0)
			(effects
				(font
					(size 1.27 1.27)
				)
				(hide yes)
			)
		)
		(property "MPN" "GRM155R61E105KE11J"
			(at 281.94 77.47 0)
			(effects
				(font
					(size 1.27 1.27)
					(thickness 0.15)
				)
				(justify left bottom)
				(hide yes)
			)
		)
		(property "Manufacturer" "Murata"
			(at 284.48 77.47 0)
			(effects
				(font
					(size 1.27 1.27)
					(thickness 0.15)
				)
				(justify left bottom)
				(hide yes)
			)
		)
		(property "License" "Apache-2.0"
			(at 287.02 77.47 0)
			(effects
				(font
					(size 1.27 1.27)
					(thickness 0.15)
				)
				(justify left bottom)
				(hide yes)
			)
		)
		(property "Author" "Antmicro"
			(at 289.56 77.47 0)
			(effects
				(font
					(size 1.27 1.27)
					(thickness 0.15)
				)
				(justify left bottom)
				(hide yes)
			)
		)
		(property "Val" "1u"
			(at 266.446 96.52 90)
			(effects
				(font
					(size 1.27 1.27)
					(thickness 0.15)
				)
				(justify right)
			)
		)
		(property "Voltage" "25V"
			(at 292.1 77.47 0)
			(effects
				(font
					(size 1.27 1.27)
				)
				(justify left bottom)
				(hide yes)
			)
		)
		(property "Dielectric" "X5R"
			(at 294.64 77.47 0)
			(effects
				(font
					(size 1.27 1.27)
				)
				(justify left bottom)
				(hide yes)
			)
		)
		(pin "2"
		)
		(pin "1"
		)
		(instances
			(project "oculink-to-pcie-adapter"
				(path ""
					(reference "C7")
					(unit 1)
				)
			)
		)
	)
	(symbol
		(lib_id "antmicroResistors0402:R_100k_0402")
		(at 92.71 210.82 90)
		(unit 1)
		(exclude_from_sim no)
		(in_bom yes)
		(on_board yes)
		(dnp no)
		(property "Reference" "R15"
			(at 93.98 207.01 90)
			(effects
				(font
					(size 1.27 1.27)
					(thickness 0.15)
				)
				(justify right)
			)
		)
		(property "Value" "R_100k_0402"
			(at 105.41 190.5 0)
			(effects
				(font
					(size 1.27 1.27)
					(thickness 0.15)
				)
				(justify left bottom)
				(hide yes)
			)
		)
		(property "Footprint" "antmicro-footprints:R_0402_1005Metric"
			(at 107.95 190.5 0)
			(effects
				(font
					(size 1.27 1.27)
					(thickness 0.15)
				)
				(justify left bottom)
				(hide yes)
			)
		)
		(property "Datasheet" "https://www.bourns.com/docs/product-datasheets/cr.pdf"
			(at 110.49 190.5 0)
			(effects
				(font
					(size 1.27 1.27)
					(thickness 0.15)
				)
				(justify left bottom)
				(hide yes)
			)
		)
		(property "Description" "SMD Chip Resistor, 100 kohm, ± 1%, 62.5 mW, 0402 [1005 Metric], Thick Film, General Purpose"
			(at 92.71 210.82 0)
			(effects
				(font
					(size 1.27 1.27)
				)
				(hide yes)
			)
		)
		(property "MPN" "CR0402-FX-1003GLF"
			(at 113.03 190.5 0)
			(effects
				(font
					(size 1.27 1.27)
					(thickness 0.15)
				)
				(justify left bottom)
				(hide yes)
			)
		)
		(property "Manufacturer" "Bourns"
			(at 115.57 190.5 0)
			(effects
				(font
					(size 1.27 1.27)
					(thickness 0.15)
				)
				(justify left bottom)
				(hide yes)
			)
		)
		(property "License" "Apache-2.0"
			(at 118.11 190.5 0)
			(effects
				(font
					(size 1.27 1.27)
					(thickness 0.15)
				)
				(justify left bottom)
				(hide yes)
			)
		)
		(property "Author" "Antmicro"
			(at 120.65 190.5 0)
			(effects
				(font
					(size 1.27 1.27)
					(thickness 0.15)
				)
				(justify left bottom)
				(hide yes)
			)
		)
		(property "Val" "100k"
			(at 93.98 209.55 90)
			(effects
				(font
					(size 1.27 1.27)
					(thickness 0.15)
				)
				(justify right)
			)
		)
		(property "Tolerance" "1%"
			(at 102.87 190.5 0)
			(effects
				(font
					(size 1.27 1.27)
				)
				(justify left bottom)
				(hide yes)
			)
		)
		(pin "1"
		)
		(pin "2"
		)
		(instances
			(project ""
				(path ""
					(reference "R15")
					(unit 1)
				)
			)
		)
	)
	(symbol
		(lib_id "antmicropower:GND")
		(at 85.09 128.27 0)
		(mirror y)
		(unit 1)
		(exclude_from_sim no)
		(in_bom yes)
		(on_board yes)
		(dnp no)
		(property "Reference" "#PWR060"
			(at 76.2 130.81 0)
			(effects
				(font
					(size 1.27 1.27)
					(thickness 0.15)
				)
				(justify left bottom)
				(hide yes)
			)
		)
		(property "Value" "GND"
			(at 85.09 132.08 0)
			(effects
				(font
					(size 1.27 1.27)
					(thickness 0.15)
				)
			)
		)
		(property "Footprint" ""
			(at 76.2 135.89 0)
			(effects
				(font
					(size 1.27 1.27)
					(thickness 0.15)
				)
				(justify left bottom)
				(hide yes)
			)
		)
		(property "Datasheet" ""
			(at 76.2 140.97 0)
			(effects
				(font
					(size 1.27 1.27)
					(thickness 0.15)
				)
				(justify left bottom)
				(hide yes)
			)
		)
		(property "Description" ""
			(at 85.09 128.27 0)
			(effects
				(font
					(size 1.27 1.27)
				)
				(hide yes)
			)
		)
		(property "Author" "Antmicro"
			(at 76.2 135.89 0)
			(effects
				(font
					(size 1.27 1.27)
					(thickness 0.15)
				)
				(justify left bottom)
				(hide yes)
			)
		)
		(property "License" "Apache-2.0"
			(at 76.2 138.43 0)
			(effects
				(font
					(size 1.27 1.27)
					(thickness 0.15)
				)
				(justify left bottom)
				(hide yes)
			)
		)
		(pin "1"
		)
		(instances
			(project "oculink-to-pcie-adapter"
				(path ""
					(reference "#PWR060")
					(unit 1)
				)
			)
		)
	)
	(symbol
		(lib_id "antmicropower:PWR_FLAG")
		(at 128.27 100.33 270)
		(unit 1)
		(exclude_from_sim no)
		(in_bom yes)
		(on_board yes)
		(dnp no)
		(fields_autoplaced yes)
		(property "Reference" "#FLG09"
			(at 130.175 100.33 0)
			(effects
				(font
					(size 1.27 1.27)
				)
				(hide yes)
			)
		)
		(property "Value" "PWR_FLAG"
			(at 132.08 100.3299 90)
			(effects
				(font
					(size 1.27 1.27)
				)
				(justify left)
			)
		)
		(property "Footprint" ""
			(at 128.27 100.33 0)
			(effects
				(font
					(size 1.27 1.27)
				)
				(hide yes)
			)
		)
		(property "Datasheet" ""
			(at 128.27 100.33 0)
			(effects
				(font
					(size 1.27 1.27)
				)
				(hide yes)
			)
		)
		(property "Description" ""
			(at 128.27 100.33 0)
			(effects
				(font
					(size 1.27 1.27)
				)
				(hide yes)
			)
		)
		(pin "1"
		)
		(instances
			(project "oculink-to-pcie-adapter"
				(path ""
					(reference "#FLG09")
					(unit 1)
				)
			)
		)
	)
	(symbol
		(lib_id "antmicropower:GND")
		(at 85.09 102.87 0)
		(mirror y)
		(unit 1)
		(exclude_from_sim no)
		(in_bom yes)
		(on_board yes)
		(dnp no)
		(property "Reference" "#PWR098"
			(at 76.2 105.41 0)
			(effects
				(font
					(size 1.27 1.27)
					(thickness 0.15)
				)
				(justify left bottom)
				(hide yes)
			)
		)
		(property "Value" "GND"
			(at 85.09 106.68 0)
			(effects
				(font
					(size 1.27 1.27)
					(thickness 0.15)
				)
			)
		)
		(property "Footprint" ""
			(at 76.2 110.49 0)
			(effects
				(font
					(size 1.27 1.27)
					(thickness 0.15)
				)
				(justify left bottom)
				(hide yes)
			)
		)
		(property "Datasheet" ""
			(at 76.2 115.57 0)
			(effects
				(font
					(size 1.27 1.27)
					(thickness 0.15)
				)
				(justify left bottom)
				(hide yes)
			)
		)
		(property "Description" ""
			(at 85.09 102.87 0)
			(effects
				(font
					(size 1.27 1.27)
				)
				(hide yes)
			)
		)
		(property "Author" "Antmicro"
			(at 76.2 110.49 0)
			(effects
				(font
					(size 1.27 1.27)
					(thickness 0.15)
				)
				(justify left bottom)
				(hide yes)
			)
		)
		(property "License" "Apache-2.0"
			(at 76.2 113.03 0)
			(effects
				(font
					(size 1.27 1.27)
					(thickness 0.15)
				)
				(justify left bottom)
				(hide yes)
			)
		)
		(pin "1"
		)
		(instances
			(project "oculink-to-pcie-adapter"
				(path ""
					(reference "#PWR098")
					(unit 1)
				)
			)
		)
	)
	(symbol
		(lib_id "antmicroCapacitorspol:C_Pol_100u_10V_KEMET-T520-B")
		(at 361.95 88.9 270)
		(unit 1)
		(exclude_from_sim no)
		(in_bom yes)
		(on_board yes)
		(dnp no)
		(fields_autoplaced yes)
		(property "Reference" "C3"
			(at 364.49 88.3666 90)
			(effects
				(font
					(size 1.27 1.27)
					(thickness 0.15)
				)
				(justify left)
			)
		)
		(property "Value" "C_Pol_100u_10V_KEMET-T520-B"
			(at 359.41 102.87 0)
			(effects
				(font
					(size 1.27 1.27)
					(thickness 0.15)
				)
				(justify left bottom)
				(hide yes)
			)
		)
		(property "Footprint" "antmicro-footprints:C_Pol_EIA-B"
			(at 354.33 102.87 0)
			(effects
				(font
					(size 1.27 1.27)
					(thickness 0.15)
				)
				(justify left bottom)
				(hide yes)
			)
		)
		(property "Datasheet" "https://www.kemet.com/en/us/capacitors/product/T520B107M010ATE070.html"
			(at 351.79 102.87 0)
			(effects
				(font
					(size 1.27 1.27)
					(thickness 0.15)
				)
				(justify left bottom)
				(hide yes)
			)
		)
		(property "Description" "Tantalum Capacitors - Polymer 10V 100uF 1311 20% ESR=70mOhms"
			(at 361.95 88.9 0)
			(effects
				(font
					(size 1.27 1.27)
				)
				(hide yes)
			)
		)
		(property "Val" "100u"
			(at 364.49 90.9066 90)
			(effects
				(font
					(size 1.27 1.27)
					(thickness 0.15)
				)
				(justify left)
			)
		)
		(property "MPN" "T520B107M010ATE070"
			(at 349.25 102.87 0)
			(effects
				(font
					(size 1.27 1.27)
					(thickness 0.15)
				)
				(justify left bottom)
				(hide yes)
			)
		)
		(property "Manufacturer" "KEMET"
			(at 346.71 102.87 0)
			(effects
				(font
					(size 1.27 1.27)
					(thickness 0.15)
				)
				(justify left bottom)
				(hide yes)
			)
		)
		(property "License" "Apache-2.0"
			(at 344.17 102.87 0)
			(effects
				(font
					(size 1.27 1.27)
					(thickness 0.15)
				)
				(justify left bottom)
				(hide yes)
			)
		)
		(property "Author" "Antmicro"
			(at 341.63 102.87 0)
			(effects
				(font
					(size 1.27 1.27)
					(thickness 0.15)
				)
				(justify left bottom)
				(hide yes)
			)
		)
		(property "Voltage" "10V"
			(at 364.49 93.4465 90)
			(effects
				(font
					(size 1.27 1.27)
				)
				(justify left)
			)
		)
		(property "Dielectric" "template_dielectric"
			(at 336.55 102.87 0)
			(effects
				(font
					(size 1.27 1.27)
				)
				(justify left bottom)
				(hide yes)
			)
		)
		(pin "2"
		)
		(pin "1"
		)
		(instances
			(project "oculink-to-pcie-adapter"
				(path ""
					(reference "C3")
					(unit 1)
				)
			)
		)
	)
	(symbol
		(lib_id "antmicroCapacitorsmisc:C_22u_25V_0805")
		(at 242.57 90.17 90)
		(unit 1)
		(exclude_from_sim no)
		(in_bom yes)
		(on_board yes)
		(dnp no)
		(fields_autoplaced yes)
		(property "Reference" "C4"
			(at 245.11 85.0836 90)
			(effects
				(font
					(size 1.27 1.27)
					(thickness 0.15)
				)
				(justify right)
			)
		)
		(property "Value" "C_22u_25V_0805"
			(at 252.73 69.85 0)
			(effects
				(font
					(size 1.27 1.27)
					(thickness 0.15)
				)
				(justify left bottom)
				(hide yes)
			)
		)
		(property "Footprint" "antmicro-footprints:C_0805_2012Metric"
			(at 255.27 69.85 0)
			(effects
				(font
					(size 1.27 1.27)
					(thickness 0.15)
				)
				(justify left bottom)
				(hide yes)
			)
		)
		(property "Datasheet" "https://product.samsungsem.com/mlcc/CL21A226MAYNNN.do"
			(at 257.81 69.85 0)
			(effects
				(font
					(size 1.27 1.27)
					(thickness 0.15)
				)
				(justify left bottom)
				(hide yes)
			)
		)
		(property "Description" "SMT Multilayer Ceramic Capacitor, 22uF, +/-20%, 25V, X5R, 0805 [2012 Metric]"
			(at 242.57 90.17 0)
			(effects
				(font
					(size 1.27 1.27)
				)
				(hide yes)
			)
		)
		(property "MPN" "CL21A226MAYNNNE"
			(at 260.35 69.85 0)
			(effects
				(font
					(size 1.27 1.27)
					(thickness 0.15)
				)
				(justify left bottom)
				(hide yes)
			)
		)
		(property "Manufacturer" "Samsung Electro-Mechanics"
			(at 262.89 69.85 0)
			(effects
				(font
					(size 1.27 1.27)
					(thickness 0.15)
				)
				(justify left bottom)
				(hide yes)
			)
		)
		(property "License" "Apache-2.0"
			(at 265.43 69.85 0)
			(effects
				(font
					(size 1.27 1.27)
					(thickness 0.15)
				)
				(justify left bottom)
				(hide yes)
			)
		)
		(property "Author" "Antmicro"
			(at 267.97 69.85 0)
			(effects
				(font
					(size 1.27 1.27)
					(thickness 0.15)
				)
				(justify left bottom)
				(hide yes)
			)
		)
		(property "Val" "22u"
			(at 245.11 87.6236 90)
			(effects
				(font
					(size 1.27 1.27)
					(thickness 0.15)
				)
				(justify right)
			)
		)
		(property "Voltage" "25V"
			(at 245.11 90.1635 90)
			(effects
				(font
					(size 1.27 1.27)
				)
				(justify right)
			)
		)
		(property "Dielectric" "X5R"
			(at 273.05 69.85 0)
			(effects
				(font
					(size 1.27 1.27)
				)
				(justify left bottom)
				(hide yes)
			)
		)
		(property "Public" "False"
			(at 275.59 69.85 0)
			(effects
				(font
					(size 1.27 1.27)
				)
				(justify left bottom)
				(hide yes)
			)
		)
		(pin "2"
		)
		(pin "1"
		)
		(instances
			(project ""
				(path ""
					(reference "C4")
					(unit 1)
				)
			)
		)
	)
	(symbol
		(lib_id "antmicropower:+3V3")
		(at 379.73 73.66 0)
		(unit 1)
		(exclude_from_sim no)
		(in_bom yes)
		(on_board yes)
		(dnp no)
		(property "Reference" "#PWR012"
			(at 394.97 73.66 0)
			(effects
				(font
					(size 1.27 1.27)
					(thickness 0.15)
				)
				(justify left bottom)
				(hide yes)
			)
		)
		(property "Value" "+3V3"
			(at 379.73 69.85 0)
			(effects
				(font
					(size 1.27 1.27)
					(thickness 0.15)
				)
			)
		)
		(property "Footprint" ""
			(at 394.97 81.28 0)
			(effects
				(font
					(size 1.27 1.27)
					(thickness 0.15)
				)
				(justify left bottom)
				(hide yes)
			)
		)
		(property "Datasheet" ""
			(at 394.97 83.82 0)
			(effects
				(font
					(size 1.27 1.27)
					(thickness 0.15)
				)
				(justify left bottom)
				(hide yes)
			)
		)
		(property "Description" ""
			(at 379.73 73.66 0)
			(effects
				(font
					(size 1.27 1.27)
				)
				(hide yes)
			)
		)
		(property "Author" "Antmicro"
			(at 394.97 76.2 0)
			(effects
				(font
					(size 1.27 1.27)
					(thickness 0.15)
				)
				(justify left bottom)
				(hide yes)
			)
		)
		(property "License" "Apache-2.0"
			(at 394.97 78.74 0)
			(effects
				(font
					(size 1.27 1.27)
					(thickness 0.15)
				)
				(justify left bottom)
				(hide yes)
			)
		)
		(pin "1"
		)
		(instances
			(project "oculink-to-pcie-adapter"
				(path ""
					(reference "#PWR012")
					(unit 1)
				)
			)
		)
	)
	(symbol
		(lib_id "antmicroLEDIndicationDiscrete:LED_G_0603_LTST-C190GKT")
		(at 304.8 208.28 90)
		(unit 1)
		(exclude_from_sim no)
		(in_bom yes)
		(on_board yes)
		(dnp no)
		(fields_autoplaced yes)
		(property "Reference" "D1"
			(at 307.34 204.47 90)
			(effects
				(font
					(size 1.27 1.27)
					(thickness 0.15)
				)
				(justify right)
			)
		)
		(property "Value" "LED_G_0603_LTST-C190GKT"
			(at 312.42 185.42 0)
			(effects
				(font
					(size 1.27 1.27)
					(thickness 0.15)
				)
				(justify left bottom)
				(hide yes)
			)
		)
		(property "Footprint" "antmicro-footprints:LED_0603_1608Metric_G"
			(at 314.96 185.42 0)
			(effects
				(font
					(size 1.27 1.27)
					(thickness 0.15)
				)
				(justify left bottom)
				(hide yes)
			)
		)
		(property "Datasheet" "https://media.digikey.com/pdf/Data%20Sheets/Lite-On%20PDFs/LTST-C190GKT.pdf"
			(at 317.5 185.42 0)
			(effects
				(font
					(size 1.27 1.27)
					(thickness 0.15)
				)
				(justify left bottom)
				(hide yes)
			)
		)
		(property "Description" "LED, Green, SMD, 0603, 20 mA, 2.1 V, 569 nm"
			(at 304.8 208.28 0)
			(effects
				(font
					(size 1.27 1.27)
				)
				(hide yes)
			)
		)
		(property "MPN" "LTST-C190GKT"
			(at 320.04 185.42 0)
			(effects
				(font
					(size 1.27 1.27)
					(thickness 0.15)
				)
				(justify left bottom)
				(hide yes)
			)
		)
		(property "Manufacturer" "Lite-On"
			(at 322.58 185.42 0)
			(effects
				(font
					(size 1.27 1.27)
					(thickness 0.15)
				)
				(justify left bottom)
				(hide yes)
			)
		)
		(property "Color" "Green"
			(at 307.34 207.0099 90)
			(effects
				(font
					(size 1.27 1.27)
				)
				(justify right)
			)
		)
		(property "Author" "Antmicro"
			(at 325.12 185.42 0)
			(effects
				(font
					(size 1.27 1.27)
					(thickness 0.15)
				)
				(justify left bottom)
				(hide yes)
			)
		)
		(property "License" "Apache-2.0"
			(at 327.66 185.42 0)
			(effects
				(font
					(size 1.27 1.27)
					(thickness 0.15)
				)
				(justify left bottom)
				(hide yes)
			)
		)
		(pin "2"
		)
		(pin "1"
		)
		(instances
			(project ""
				(path ""
					(reference "D1")
					(unit 1)
				)
			)
		)
	)
	(symbol
		(lib_id "antmicropower:GND")
		(at 304.8 233.68 0)
		(mirror y)
		(unit 1)
		(exclude_from_sim no)
		(in_bom yes)
		(on_board yes)
		(dnp no)
		(property "Reference" "#PWR027"
			(at 295.91 236.22 0)
			(effects
				(font
					(size 1.27 1.27)
					(thickness 0.15)
				)
				(justify left bottom)
				(hide yes)
			)
		)
		(property "Value" "GND"
			(at 304.8 237.49 0)
			(effects
				(font
					(size 1.27 1.27)
					(thickness 0.15)
				)
			)
		)
		(property "Footprint" ""
			(at 295.91 241.3 0)
			(effects
				(font
					(size 1.27 1.27)
					(thickness 0.15)
				)
				(justify left bottom)
				(hide yes)
			)
		)
		(property "Datasheet" ""
			(at 295.91 246.38 0)
			(effects
				(font
					(size 1.27 1.27)
					(thickness 0.15)
				)
				(justify left bottom)
				(hide yes)
			)
		)
		(property "Description" ""
			(at 304.8 233.68 0)
			(effects
				(font
					(size 1.27 1.27)
				)
				(hide yes)
			)
		)
		(property "Author" "Antmicro"
			(at 295.91 241.3 0)
			(effects
				(font
					(size 1.27 1.27)
					(thickness 0.15)
				)
				(justify left bottom)
				(hide yes)
			)
		)
		(property "License" "Apache-2.0"
			(at 295.91 243.84 0)
			(effects
				(font
					(size 1.27 1.27)
					(thickness 0.15)
				)
				(justify left bottom)
				(hide yes)
			)
		)
		(pin "1"
		)
		(instances
			(project "oculink-to-pcie-adapter"
				(path ""
					(reference "#PWR027")
					(unit 1)
				)
			)
		)
	)
	(sheet
		(at 95.25 88.9)
		(size 25.4 7.62)
		(exclude_from_sim no)
		(in_bom yes)
		(on_board yes)
		(dnp no)
		(fields_autoplaced yes)
		(stroke
			(width 0.1524)
			(type solid)
		)
		(fill
			(color 0 0 0 0.0000)
		)
		(property "Sheetname" "Ideal-diode-1"
			(at 95.25 88.1884 0)
			(effects
				(font
					(size 1.27 1.27)
				)
				(justify left bottom)
			)
		)
		(property "Sheetfile" "ideal-diode.kicad_sch"
			(at 95.25 97.1046 0)
			(effects
				(font
					(size 1.27 1.27)
				)
				(justify left top)
			)
		)
		(pin "VIN" input
			(at 95.25 92.71 180)
			(effects
				(font
					(size 1.27 1.27)
				)
				(justify left)
			)
		)
		(pin "VOUT" output
			(at 120.65 92.71 0)
			(effects
				(font
					(size 1.27 1.27)
				)
				(justify right)
			)
		)
		(instances
			(project "oculink-to-pcie-adapter"
				(path ""
					(page "7")
				)
			)
		)
	)
	(sheet
		(at 95.25 63.5)
		(size 25.4 7.62)
		(exclude_from_sim no)
		(in_bom yes)
		(on_board yes)
		(dnp no)
		(fields_autoplaced yes)
		(stroke
			(width 0.1524)
			(type solid)
		)
		(fill
			(color 0 0 0 0.0000)
		)
		(property "Sheetname" "Ideal-diode-0"
			(at 95.25 62.7884 0)
			(effects
				(font
					(size 1.27 1.27)
				)
				(justify left bottom)
			)
		)
		(property "Sheetfile" "ideal-diode.kicad_sch"
			(at 95.25 71.7046 0)
			(effects
				(font
					(size 1.27 1.27)
				)
				(justify left top)
			)
		)
		(pin "VIN" input
			(at 95.25 67.31 180)
			(effects
				(font
					(size 1.27 1.27)
				)
				(justify left)
			)
		)
		(pin "VOUT" output
			(at 120.65 67.31 0)
			(effects
				(font
					(size 1.27 1.27)
				)
				(justify right)
			)
		)
		(instances
			(project "oculink-to-pcie-adapter"
				(path ""
					(page "6")
				)
			)
		)
	)
	(sheet
		(at 95.25 114.3)
		(size 25.4 7.62)
		(exclude_from_sim no)
		(in_bom yes)
		(on_board yes)
		(dnp no)
		(fields_autoplaced yes)
		(stroke
			(width 0.1524)
			(type solid)
		)
		(fill
			(color 0 0 0 0.0000)
		)
		(property "Sheetname" "Ideal-diode-2"
			(at 95.25 113.5884 0)
			(effects
				(font
					(size 1.27 1.27)
				)
				(justify left bottom)
			)
		)
		(property "Sheetfile" "ideal-diode.kicad_sch"
			(at 95.25 122.5046 0)
			(effects
				(font
					(size 1.27 1.27)
				)
				(justify left top)
			)
		)
		(pin "VIN" input
			(at 95.25 118.11 180)
			(effects
				(font
					(size 1.27 1.27)
				)
				(justify left)
			)
		)
		(pin "VOUT" output
			(at 120.65 118.11 0)
			(effects
				(font
					(size 1.27 1.27)
				)
				(justify right)
			)
		)
		(instances
			(project "oculink-to-pcie-adapter"
				(path ""
					(page "9")
				)
			)
		)
	)
)
